FILE_TYPE = MACRO_DRAWING;
SET COLOR_WIRE YELLOW;
SET COLOR_PROP ORANGE;
SET COLOR_DOT WHITE;
SET COLOR_ARC YELLOW;
SET COLOR_BODY GREEN;
SET COLOR_NOTE PURPLE;
SET PROP_DISPLAY VALUE;
SET PAGE_NUMBER P190;
FORCEADD OFFPAGE..1
(-7125 4125);
FORCEPROP 2 LAST $XR0 186 
J 0
(-7407 4125);
DISPLAY 0.638298 (-7407 4125);
PAINT MONO (-7407 4125);
FORCEPROP 2 LAST CDS_LIB standard
J 2
(-7125 4125);
DISPLAY INVISIBLE (-7125 4125);
FORCEPROP 1 LAST OFFPAGE TRUE
J 0
(-6800 4000);
DISPLAY 0.872340 (-6800 4000);
PAINT GREEN (-6800 4000);
DISPLAY INVISIBLE (-6800 4000);
FORCEPROP 1 LAST COMMENT_BODY TRUE
J 0
(-7000 4025);
DISPLAY 0.872340 (-7000 4025);
PAINT GREEN (-7000 4025);
DISPLAY INVISIBLE (-7000 4025);
FORCEPROP 2 LAST PATH I1
J 0
(-7075 4200);
DISPLAY 1.021277 (-7075 4200);
DISPLAY INVISIBLE (-7075 4200);
FORCEADD OFFPAGE..2
R 2
(-7175 4725);
FORCEPROP 2 LAST $XR0 186 
J 0
(-7430 4725);
DISPLAY 0.638298 (-7430 4725);
PAINT MONO (-7430 4725);
FORCEPROP 2 LAST CDS_LIB standard
J 2
(-7175 4725);
DISPLAY INVISIBLE (-7175 4725);
FORCEPROP 1 LAST OFFPAGE TRUE
J 2
(-7500 4600);
DISPLAY 0.872340 (-7500 4600);
PAINT GREEN (-7500 4600);
DISPLAY INVISIBLE (-7500 4600);
FORCEPROP 1 LAST COMMENT_BODY TRUE
J 2
(-7130 4630);
DISPLAY 0.872340 (-7130 4630);
PAINT GREEN (-7130 4630);
DISPLAY INVISIBLE (-7130 4630);
FORCEPROP 2 LAST PATH I10
J 0
(-7125 4800);
DISPLAY 1.021277 (-7125 4800);
DISPLAY INVISIBLE (-7125 4800);
FORCEADD VCC_CORE..1
(-3900 5850);
FORCEPROP 3 LASTPIN (-3900 5800) SIG_NAME SW_P12V_STBY_PVDDCR_SOC_P1_FLT\g
J 0
(-3890 5810);
DISPLAY 0.659574 (-3890 5810);
PAINT MONO (-3890 5810);
DISPLAY INVISIBLE (-3890 5810);
FORCEPROP 1 LAST HDL_POWER SW_P12V_STBY_PVDDCR_SOC_P1_FLT
J 1
(-3900 5900);
DISPLAY 0.489362 (-3900 5900);
PAINT GREEN (-3900 5900);
FORCEPROP 2 LAST CDS_LIB pure_quanta_power
J 0
(-3900 5850);
DISPLAY INVISIBLE (-3900 5850);
FORCEPROP 1 LAST PATH I102
J 0
(-3850 5875);
DISPLAY 0.872340 (-3850 5875);
PAINT AQUA (-3850 5875);
DISPLAY INVISIBLE (-3850 5875);
FORCEADD VCC_CORE..1
(-1425 3325);
FORCEPROP 3 LASTPIN (-1425 3275) SIG_NAME PVDDCR_SOC_P1\g
J 0
(-1415 3285);
DISPLAY 0.659574 (-1415 3285);
PAINT MONO (-1415 3285);
DISPLAY INVISIBLE (-1415 3285);
FORCEPROP 1 LAST HDL_POWER PVDDCR_SOC_P1
J 1
(-1425 3375);
DISPLAY 0.489362 (-1425 3375);
PAINT GREEN (-1425 3375);
FORCEPROP 2 LAST CDS_LIB pure_quanta_power
J 0
(-1425 3325);
DISPLAY INVISIBLE (-1425 3325);
FORCEPROP 1 LAST PATH I104
J 0
(-1375 3350);
DISPLAY 0.872340 (-1375 3350);
PAINT AQUA (-1375 3350);
DISPLAY INVISIBLE (-1375 3350);
FORCEADD UNIVERSAL_GND..1
(-1425 2700);
FORCEPROP 3 LASTPIN (-1425 2750) SIG_NAME GND\g
J 0
(-1415 2760);
DISPLAY 0.659574 (-1415 2760);
PAINT MONO (-1415 2760);
DISPLAY INVISIBLE (-1415 2760);
FORCEPROP 2 LAST CDS_LIB pure_quanta_power
J 0
(-1425 2700);
DISPLAY INVISIBLE (-1425 2700);
FORCEPROP 1 LAST PATH I105
J 0
(-1350 2700);
DISPLAY 0.872340 (-1350 2700);
PAINT AQUA (-1350 2700);
DISPLAY INVISIBLE (-1350 2700);
FORCEPROP 1 LAST HDL_POWER GND
J 1
(-1400 2625);
DISPLAY 0.872340 (-1400 2625);
PAINT GREEN (-1400 2625);
DISPLAY INVISIBLE (-1400 2625);
FORCEADD Q_CAPP..1
(-3425 5575);
FORCEPROP 1 LAST LOCATION PC336
J 0
(-3375 5675);
DISPLAY 0.489362 (-3375 5675);
PAINT SKYBLUE (-3375 5675);
FORCEPROP 0 LAST $SEC 1
J 0
(-3375 5725);
DISPLAY 0.680851 (-3375 5725);
PAINT MONO (-3375 5725);
DISPLAY INVISIBLE (-3375 5725);
FORCEPROP 0 LAST CDS_SEC 1
J 0
(-3375 5725);
DISPLAY 1.021277 (-3375 5725);
DISPLAY INVISIBLE (-3375 5725);
FORCEPROP 1 LASTPIN (-3425 5675) $PN 1
J 0
(-3415 5660);
DISPLAY 0.489362 (-3415 5660);
PAINT MONO (-3415 5660);
FORCEPROP 1 LASTPIN (-3425 5475) $PN 2
J 0
(-3415 5460);
DISPLAY 0.489362 (-3415 5460);
PAINT MONO (-3415 5460);
FORCEPROP 1 LAST VOLTAGE 25V
J 0
(-3375 5525);
DISPLAY 0.489362 (-3375 5525);
PAINT SKYBLUE (-3375 5525);
FORCEPROP 1 LAST MATERIAL OSCON
J 0
(-3375 5475);
DISPLAY 0.489362 (-3375 5475);
PAINT SKYBLUE (-3375 5475);
FORCEPROP 1 LAST PACK_TYPE THLF
J 0
(-3375 5425);
DISPLAY 0.489362 (-3375 5425);
PAINT SKYBLUE (-3375 5425);
FORCEPROP 1 LAST PART_NUMBER CC72204MD02
J 0
(-3375 5375);
DISPLAY 0.489362 (-3375 5375);
PAINT SKYBLUE (-3375 5375);
FORCEPROP 1 LAST TOLERANCE 20%
J 0
(-3375 5575);
DISPLAY 0.489362 (-3375 5575);
PAINT SKYBLUE (-3375 5575);
FORCEPROP 1 LAST VALUE 220UF
J 0
(-3375 5625);
DISPLAY 0.489362 (-3375 5625);
PAINT SKYBLUE (-3375 5625);
FORCEPROP 2 LAST CDS_LIB pure_quanta
J 0
(-3425 5575);
DISPLAY INVISIBLE (-3425 5575);
FORCEPROP 1 LAST PATH I106
J 0
(-3375 5725);
DISPLAY 0.978723 (-3375 5725);
DISPLAY INVISIBLE (-3375 5725);
FORCEADD Q_CAPP..1
(-1425 3050);
FORCEPROP 1 LAST LOCATION PC343
J 0
(-1375 3150);
DISPLAY 0.489362 (-1375 3150);
PAINT SKYBLUE (-1375 3150);
FORCEPROP 0 LAST $SEC 1
J 0
(-1375 3200);
DISPLAY 0.680851 (-1375 3200);
PAINT MONO (-1375 3200);
DISPLAY INVISIBLE (-1375 3200);
FORCEPROP 0 LAST CDS_SEC 1
J 0
(-1375 3200);
DISPLAY 1.021277 (-1375 3200);
DISPLAY INVISIBLE (-1375 3200);
FORCEPROP 1 LASTPIN (-1425 3150) $PN 1
J 0
(-1415 3135);
DISPLAY 0.489362 (-1415 3135);
PAINT MONO (-1415 3135);
FORCEPROP 1 LASTPIN (-1425 2950) $PN 2
J 0
(-1415 2935);
DISPLAY 0.489362 (-1415 2935);
PAINT MONO (-1415 2935);
FORCEPROP 1 LAST TOLERANCE 20%
J 0
(-1375 3050);
DISPLAY 0.489362 (-1375 3050);
PAINT SKYBLUE (-1375 3050);
FORCEPROP 1 LAST VALUE 470UF
J 0
(-1375 3100);
DISPLAY 0.489362 (-1375 3100);
PAINT SKYBLUE (-1375 3100);
FORCEPROP 1 LAST MATERIAL SPCAP
J 0
(-1375 2950);
DISPLAY 0.489362 (-1375 2950);
PAINT SKYBLUE (-1375 2950);
FORCEPROP 1 LAST PART_NUMBER CH747LM8825
J 0
(-1375 2850);
DISPLAY 0.489362 (-1375 2850);
PAINT SKYBLUE (-1375 2850);
FORCEPROP 1 LAST VOLTAGE 2.5V
J 0
(-1375 3000);
DISPLAY 0.489362 (-1375 3000);
PAINT SKYBLUE (-1375 3000);
FORCEPROP 1 LAST PACK_TYPE SMLF
J 0
(-1375 2900);
DISPLAY 0.489362 (-1375 2900);
PAINT SKYBLUE (-1375 2900);
FORCEPROP 2 LAST CDS_LIB pure_quanta
J 0
(-1425 3050);
DISPLAY INVISIBLE (-1425 3050);
FORCEPROP 1 LAST PATH I107
J 0
(-1375 3200);
DISPLAY 0.978723 (-1375 3200);
DISPLAY INVISIBLE (-1375 3200);
FORCEADD Q_CAP..1
(-5425 5575);
FORCEPROP 1 LAST LOCATION PC323_1
J 0
(-5375 5675);
DISPLAY 0.489362 (-5375 5675);
PAINT SKYBLUE (-5375 5675);
FORCEPROP 0 LAST $SEC 1
J 0
(-5375 5725);
DISPLAY 0.680851 (-5375 5725);
PAINT MONO (-5375 5725);
DISPLAY INVISIBLE (-5375 5725);
FORCEPROP 0 LAST CDS_SEC 1
J 0
(-5375 5725);
DISPLAY 1.021277 (-5375 5725);
DISPLAY INVISIBLE (-5375 5725);
FORCEPROP 1 LASTPIN (-5425 5675) $PN 1
J 0
(-5415 5655);
DISPLAY 0.489362 (-5415 5655);
PAINT MONO (-5415 5655);
FORCEPROP 1 LASTPIN (-5425 5475) $PN 2
J 0
(-5415 5455);
DISPLAY 0.489362 (-5415 5455);
PAINT MONO (-5415 5455);
FORCEPROP 1 LAST MATERIAL X7R
J 0
(-5375 5475);
DISPLAY 0.489362 (-5375 5475);
PAINT SKYBLUE (-5375 5475);
FORCEPROP 1 LAST TOLERANCE 10%
J 0
(-5375 5525);
DISPLAY 0.489362 (-5375 5525);
PAINT SKYBLUE (-5375 5525);
FORCEPROP 1 LAST VALUE 0.1UF
J 0
(-5375 5625);
DISPLAY 0.489362 (-5375 5625);
PAINT SKYBLUE (-5375 5625);
FORCEPROP 1 LAST PART_NUMBER CH4104K1B00
J 0
(-5375 5425);
DISPLAY 0.489362 (-5375 5425);
PAINT SKYBLUE (-5375 5425);
FORCEPROP 1 LAST VOLTAGE 25V
J 0
(-5375 5575);
DISPLAY 0.489362 (-5375 5575);
PAINT SKYBLUE (-5375 5575);
FORCEPROP 1 LAST PACK_TYPE 0402
J 0
(-5375 5375);
DISPLAY 0.489362 (-5375 5375);
PAINT SKYBLUE (-5375 5375);
FORCEPROP 2 LAST CDS_LIB pure_quanta
J 0
(-5425 5575);
DISPLAY INVISIBLE (-5425 5575);
FORCEPROP 1 LAST PATH I108
J 0
(-5375 5725);
DISPLAY 0.978723 (-5375 5725);
PAINT WHITE (-5375 5725);
DISPLAY INVISIBLE (-5375 5725);
FORCEADD Q_CAP..1
(-5350 2850);
FORCEPROP 1 LAST LOCATION PC324_2
J 0
(-5300 2950);
DISPLAY 0.489362 (-5300 2950);
PAINT SKYBLUE (-5300 2950);
FORCEPROP 0 LAST $SEC 1
J 0
(-5300 3000);
DISPLAY 0.680851 (-5300 3000);
PAINT MONO (-5300 3000);
DISPLAY INVISIBLE (-5300 3000);
FORCEPROP 0 LAST CDS_SEC 1
J 0
(-5300 3000);
DISPLAY 1.021277 (-5300 3000);
DISPLAY INVISIBLE (-5300 3000);
FORCEPROP 1 LASTPIN (-5350 2950) $PN 1
J 0
(-5340 2930);
DISPLAY 0.489362 (-5340 2930);
PAINT MONO (-5340 2930);
FORCEPROP 1 LASTPIN (-5350 2750) $PN 2
J 0
(-5340 2730);
DISPLAY 0.489362 (-5340 2730);
PAINT MONO (-5340 2730);
FORCEPROP 1 LAST MATERIAL X7R
J 0
(-5300 2750);
DISPLAY 0.489362 (-5300 2750);
PAINT SKYBLUE (-5300 2750);
FORCEPROP 1 LAST TOLERANCE 10%
J 0
(-5300 2800);
DISPLAY 0.489362 (-5300 2800);
PAINT SKYBLUE (-5300 2800);
FORCEPROP 1 LAST VALUE 0.1UF
J 0
(-5300 2900);
DISPLAY 0.489362 (-5300 2900);
PAINT SKYBLUE (-5300 2900);
FORCEPROP 1 LAST PART_NUMBER CH4104K1B00
J 0
(-5300 2700);
DISPLAY 0.489362 (-5300 2700);
PAINT SKYBLUE (-5300 2700);
FORCEPROP 1 LAST VOLTAGE 25V
J 0
(-5300 2850);
DISPLAY 0.489362 (-5300 2850);
PAINT SKYBLUE (-5300 2850);
FORCEPROP 1 LAST PACK_TYPE 0402
J 0
(-5300 2650);
DISPLAY 0.489362 (-5300 2650);
PAINT SKYBLUE (-5300 2650);
FORCEPROP 2 LAST CDS_LIB pure_quanta
J 0
(-5350 2850);
DISPLAY INVISIBLE (-5350 2850);
FORCEPROP 1 LAST PATH I109
J 0
(-5300 3000);
DISPLAY 0.978723 (-5300 3000);
PAINT WHITE (-5300 3000);
DISPLAY INVISIBLE (-5300 3000);
FORCEADD Q_CAP..1
(-7525 5075);
FORCEPROP 1 LAST LOCATION PC319
J 0
(-7475 5175);
DISPLAY 0.489362 (-7475 5175);
PAINT SKYBLUE (-7475 5175);
FORCEPROP 0 LAST $SEC 1
J 0
(-7475 5225);
DISPLAY 0.680851 (-7475 5225);
PAINT MONO (-7475 5225);
DISPLAY INVISIBLE (-7475 5225);
FORCEPROP 0 LAST CDS_SEC 1
J 0
(-7475 5225);
DISPLAY 1.021277 (-7475 5225);
DISPLAY INVISIBLE (-7475 5225);
FORCEPROP 1 LASTPIN (-7525 5175) $PN 1
J 0
(-7515 5155);
DISPLAY 0.489362 (-7515 5155);
PAINT MONO (-7515 5155);
FORCEPROP 1 LASTPIN (-7525 4975) $PN 2
J 0
(-7515 4955);
DISPLAY 0.489362 (-7515 4955);
PAINT MONO (-7515 4955);
FORCEPROP 1 LAST MATERIAL X6S
J 0
(-7475 4975);
DISPLAY 0.489362 (-7475 4975);
PAINT SKYBLUE (-7475 4975);
FORCEPROP 1 LAST TOLERANCE 10%
J 0
(-7475 5025);
DISPLAY 0.489362 (-7475 5025);
PAINT SKYBLUE (-7475 5025);
FORCEPROP 1 LAST VALUE 2.2UF
J 0
(-7475 5125);
DISPLAY 0.489362 (-7475 5125);
PAINT SKYBLUE (-7475 5125);
FORCEPROP 1 LAST PART_NUMBER CH5222KEB01
J 0
(-7475 4925);
DISPLAY 0.489362 (-7475 4925);
PAINT SKYBLUE (-7475 4925);
FORCEPROP 1 LAST VOLTAGE 10V
J 0
(-7475 5075);
DISPLAY 0.489362 (-7475 5075);
PAINT SKYBLUE (-7475 5075);
FORCEPROP 1 LAST PACK_TYPE C0402
J 0
(-7475 4875);
DISPLAY 0.489362 (-7475 4875);
PAINT SKYBLUE (-7475 4875);
FORCEPROP 2 LAST CDS_LIB pure_quanta
J 0
(-7525 5075);
DISPLAY INVISIBLE (-7525 5075);
FORCEPROP 1 LAST PATH I110
J 0
(-7475 5225);
DISPLAY 0.978723 (-7475 5225);
PAINT WHITE (-7475 5225);
DISPLAY INVISIBLE (-7475 5225);
FORCEADD UNIVERSAL_GND..1
(-7525 4875);
FORCEPROP 3 LASTPIN (-7525 4925) SIG_NAME GND\g
J 0
(-7515 4935);
DISPLAY 0.659574 (-7515 4935);
PAINT MONO (-7515 4935);
DISPLAY INVISIBLE (-7515 4935);
FORCEPROP 2 LAST CDS_LIB pure_quanta_power
J 0
(-7525 4875);
DISPLAY INVISIBLE (-7525 4875);
FORCEPROP 1 LAST PATH I111
J 0
(-7450 4875);
DISPLAY 0.872340 (-7450 4875);
PAINT AQUA (-7450 4875);
DISPLAY INVISIBLE (-7450 4875);
FORCEPROP 1 LAST HDL_POWER GND
J 1
(-7500 4800);
DISPLAY 0.872340 (-7500 4800);
PAINT GREEN (-7500 4800);
DISPLAY INVISIBLE (-7500 4800);
FORCEADD UNIVERSAL_GND..1
(-7175 5375);
FORCEPROP 3 LASTPIN (-7175 5425) SIG_NAME GND\g
J 0
(-7165 5435);
DISPLAY 0.659574 (-7165 5435);
PAINT MONO (-7165 5435);
DISPLAY INVISIBLE (-7165 5435);
FORCEPROP 2 LAST CDS_LIB pure_quanta_power
J 0
(-7175 5375);
DISPLAY INVISIBLE (-7175 5375);
FORCEPROP 1 LAST PATH I112
J 0
(-7100 5375);
DISPLAY 0.872340 (-7100 5375);
PAINT AQUA (-7100 5375);
DISPLAY INVISIBLE (-7100 5375);
FORCEPROP 1 LAST HDL_POWER GND
J 1
(-7150 5300);
DISPLAY 0.872340 (-7150 5300);
PAINT GREEN (-7150 5300);
DISPLAY INVISIBLE (-7150 5300);
FORCEADD Q_RES..2
(-7525 5625);
FORCEPROP 1 LAST LOCATION PR205
J 0
(-7480 5750);
DISPLAY 0.489362 (-7480 5750);
PAINT SKYBLUE (-7480 5750);
FORCEPROP 0 LAST $SEC 1
J 0
(-7475 5800);
DISPLAY 0.680851 (-7475 5800);
PAINT MONO (-7475 5800);
DISPLAY INVISIBLE (-7475 5800);
FORCEPROP 0 LAST CDS_SEC 1
J 0
(-7475 5800);
DISPLAY 1.021277 (-7475 5800);
DISPLAY INVISIBLE (-7475 5800);
FORCEPROP 1 LASTPIN (-7525 5725) $PN 1
J 0
(-7520 5687);
DISPLAY 0.489362 (-7520 5687);
PAINT MONO (-7520 5687);
FORCEPROP 1 LASTPIN (-7525 5525) $PN 2
J 0
(-7520 5535);
DISPLAY 0.489362 (-7520 5535);
PAINT MONO (-7520 5535);
FORCEPROP 1 LAST WATTAGE 1/16W
J 0
(-7475 5600);
DISPLAY 0.489362 (-7475 5600);
PAINT SKYBLUE (-7475 5600);
FORCEPROP 1 LAST MATERIAL CHIP
J 0
(-7475 5550);
DISPLAY 0.489362 (-7475 5550);
PAINT SKYBLUE (-7475 5550);
FORCEPROP 1 LAST VALUE 2.2
J 0
(-7475 5700);
DISPLAY 0.489362 (-7475 5700);
PAINT SKYBLUE (-7475 5700);
FORCEPROP 1 LAST PART_NUMBER CS-2202FB00
J 0
(-7475 5500);
DISPLAY 0.489362 (-7475 5500);
PAINT SKYBLUE (-7475 5500);
FORCEPROP 1 LAST PACK_TYPE 0402LF
J 0
(-7475 5450);
DISPLAY 0.489362 (-7475 5450);
PAINT SKYBLUE (-7475 5450);
FORCEPROP 1 LAST TOLERANCE 1%
J 0
(-7475 5650);
DISPLAY 0.489362 (-7475 5650);
PAINT SKYBLUE (-7475 5650);
FORCEPROP 2 LAST CDS_LIB pure_quanta
J 0
(-7525 5625);
DISPLAY INVISIBLE (-7525 5625);
FORCEPROP 1 LAST PATH I113
J 0
(-7475 5800);
DISPLAY 0.978723 (-7475 5800);
PAINT WHITE (-7475 5800);
DISPLAY INVISIBLE (-7475 5800);
FORCEADD Q_CAP..1
(-7175 5650);
FORCEPROP 1 LAST LOCATION PC321_SOP1_1
J 0
(-7125 5750);
DISPLAY 0.489362 (-7125 5750);
PAINT SKYBLUE (-7125 5750);
FORCEPROP 0 LAST $SEC 1
J 0
(-7125 5800);
DISPLAY 0.680851 (-7125 5800);
PAINT MONO (-7125 5800);
DISPLAY INVISIBLE (-7125 5800);
FORCEPROP 0 LAST CDS_SEC 1
J 0
(-7125 5800);
DISPLAY 1.021277 (-7125 5800);
DISPLAY INVISIBLE (-7125 5800);
FORCEPROP 1 LASTPIN (-7175 5750) $PN 1
J 0
(-7165 5730);
DISPLAY 0.489362 (-7165 5730);
PAINT MONO (-7165 5730);
FORCEPROP 1 LASTPIN (-7175 5550) $PN 2
J 0
(-7165 5530);
DISPLAY 0.489362 (-7165 5530);
PAINT MONO (-7165 5530);
FORCEPROP 1 LAST MATERIAL X6S
J 0
(-7125 5550);
DISPLAY 0.489362 (-7125 5550);
PAINT SKYBLUE (-7125 5550);
FORCEPROP 1 LAST TOLERANCE 10%
J 0
(-7125 5600);
DISPLAY 0.489362 (-7125 5600);
PAINT SKYBLUE (-7125 5600);
FORCEPROP 1 LAST VALUE 2.2UF
J 0
(-7125 5700);
DISPLAY 0.489362 (-7125 5700);
PAINT SKYBLUE (-7125 5700);
FORCEPROP 1 LAST PART_NUMBER CH5222KEB01
J 0
(-7125 5500);
DISPLAY 0.489362 (-7125 5500);
PAINT SKYBLUE (-7125 5500);
FORCEPROP 1 LAST VOLTAGE 10V
J 0
(-7125 5650);
DISPLAY 0.489362 (-7125 5650);
PAINT SKYBLUE (-7125 5650);
FORCEPROP 1 LAST PACK_TYPE C0402
J 0
(-7125 5450);
DISPLAY 0.489362 (-7125 5450);
PAINT SKYBLUE (-7125 5450);
FORCEPROP 2 LAST CDS_LIB pure_quanta
J 0
(-7175 5650);
DISPLAY INVISIBLE (-7175 5650);
FORCEPROP 1 LAST PATH I114
J 0
(-7125 5800);
DISPLAY 0.978723 (-7125 5800);
PAINT WHITE (-7125 5800);
DISPLAY INVISIBLE (-7125 5800);
FORCEADD VCC_CORE..1
(-7525 6025);
FORCEPROP 3 LASTPIN (-7525 5975) SIG_NAME PVDDCR_CPU0_P1_PVCC\g
J 0
(-7515 5985);
DISPLAY 0.659574 (-7515 5985);
PAINT MONO (-7515 5985);
DISPLAY INVISIBLE (-7515 5985);
FORCEPROP 1 LAST HDL_POWER PVDDCR_CPU0_P1_PVCC
J 1
(-7525 6075);
DISPLAY 0.489362 (-7525 6075);
PAINT GREEN (-7525 6075);
FORCEPROP 2 LAST CDS_LIB pure_quanta_power
J 0
(-7525 6025);
DISPLAY INVISIBLE (-7525 6025);
FORCEPROP 1 LAST PATH I115
J 0
(-7475 6050);
DISPLAY 0.872340 (-7475 6050);
PAINT AQUA (-7475 6050);
DISPLAY INVISIBLE (-7475 6050);
FORCEADD Q_CAP..1
(-7500 2300);
FORCEPROP 1 LAST LOCATION PC320
J 0
(-7450 2400);
DISPLAY 0.489362 (-7450 2400);
PAINT SKYBLUE (-7450 2400);
FORCEPROP 0 LAST $SEC 1
J 0
(-7450 2450);
DISPLAY 0.680851 (-7450 2450);
PAINT MONO (-7450 2450);
DISPLAY INVISIBLE (-7450 2450);
FORCEPROP 0 LAST CDS_SEC 1
J 0
(-7450 2450);
DISPLAY 1.021277 (-7450 2450);
DISPLAY INVISIBLE (-7450 2450);
FORCEPROP 1 LASTPIN (-7500 2400) $PN 1
J 0
(-7490 2380);
DISPLAY 0.489362 (-7490 2380);
PAINT MONO (-7490 2380);
FORCEPROP 1 LASTPIN (-7500 2200) $PN 2
J 0
(-7490 2180);
DISPLAY 0.489362 (-7490 2180);
PAINT MONO (-7490 2180);
FORCEPROP 1 LAST MATERIAL X6S
J 0
(-7450 2200);
DISPLAY 0.489362 (-7450 2200);
PAINT SKYBLUE (-7450 2200);
FORCEPROP 1 LAST TOLERANCE 10%
J 0
(-7450 2250);
DISPLAY 0.489362 (-7450 2250);
PAINT SKYBLUE (-7450 2250);
FORCEPROP 1 LAST VALUE 2.2UF
J 0
(-7450 2350);
DISPLAY 0.489362 (-7450 2350);
PAINT SKYBLUE (-7450 2350);
FORCEPROP 1 LAST PART_NUMBER CH5222KEB01
J 0
(-7450 2150);
DISPLAY 0.489362 (-7450 2150);
PAINT SKYBLUE (-7450 2150);
FORCEPROP 1 LAST VOLTAGE 10V
J 0
(-7450 2300);
DISPLAY 0.489362 (-7450 2300);
PAINT SKYBLUE (-7450 2300);
FORCEPROP 1 LAST PACK_TYPE C0402
J 0
(-7450 2100);
DISPLAY 0.489362 (-7450 2100);
PAINT SKYBLUE (-7450 2100);
FORCEPROP 2 LAST CDS_LIB pure_quanta
J 0
(-7500 2300);
DISPLAY INVISIBLE (-7500 2300);
FORCEPROP 1 LAST PATH I116
J 0
(-7450 2450);
DISPLAY 0.978723 (-7450 2450);
PAINT WHITE (-7450 2450);
DISPLAY INVISIBLE (-7450 2450);
FORCEADD UNIVERSAL_GND..1
(-7500 2100);
FORCEPROP 3 LASTPIN (-7500 2150) SIG_NAME GND\g
J 0
(-7490 2160);
DISPLAY 0.659574 (-7490 2160);
PAINT MONO (-7490 2160);
DISPLAY INVISIBLE (-7490 2160);
FORCEPROP 2 LAST CDS_LIB pure_quanta_power
J 0
(-7500 2100);
DISPLAY INVISIBLE (-7500 2100);
FORCEPROP 1 LAST PATH I117
J 0
(-7425 2100);
DISPLAY 0.872340 (-7425 2100);
PAINT AQUA (-7425 2100);
DISPLAY INVISIBLE (-7425 2100);
FORCEPROP 1 LAST HDL_POWER GND
J 1
(-7475 2025);
DISPLAY 0.872340 (-7475 2025);
PAINT GREEN (-7475 2025);
DISPLAY INVISIBLE (-7475 2025);
FORCEADD UNIVERSAL_GND..1
(-7150 2600);
FORCEPROP 3 LASTPIN (-7150 2650) SIG_NAME GND\g
J 0
(-7140 2660);
DISPLAY 0.659574 (-7140 2660);
PAINT MONO (-7140 2660);
DISPLAY INVISIBLE (-7140 2660);
FORCEPROP 2 LAST CDS_LIB pure_quanta_power
J 0
(-7150 2600);
DISPLAY INVISIBLE (-7150 2600);
FORCEPROP 1 LAST PATH I118
J 0
(-7075 2600);
DISPLAY 0.872340 (-7075 2600);
PAINT AQUA (-7075 2600);
DISPLAY INVISIBLE (-7075 2600);
FORCEPROP 1 LAST HDL_POWER GND
J 1
(-7125 2525);
DISPLAY 0.872340 (-7125 2525);
PAINT GREEN (-7125 2525);
DISPLAY INVISIBLE (-7125 2525);
FORCEADD Q_RES..2
(-7500 2850);
FORCEPROP 1 LAST LOCATION PR206
J 0
(-7455 2975);
DISPLAY 0.489362 (-7455 2975);
PAINT SKYBLUE (-7455 2975);
FORCEPROP 0 LAST $SEC 1
J 0
(-7450 3025);
DISPLAY 0.680851 (-7450 3025);
PAINT MONO (-7450 3025);
DISPLAY INVISIBLE (-7450 3025);
FORCEPROP 0 LAST CDS_SEC 1
J 0
(-7450 3025);
DISPLAY 1.021277 (-7450 3025);
DISPLAY INVISIBLE (-7450 3025);
FORCEPROP 1 LASTPIN (-7500 2950) $PN 1
J 0
(-7495 2912);
DISPLAY 0.489362 (-7495 2912);
PAINT MONO (-7495 2912);
FORCEPROP 1 LASTPIN (-7500 2750) $PN 2
J 0
(-7495 2760);
DISPLAY 0.489362 (-7495 2760);
PAINT MONO (-7495 2760);
FORCEPROP 1 LAST WATTAGE 1/16W
J 0
(-7450 2825);
DISPLAY 0.489362 (-7450 2825);
PAINT SKYBLUE (-7450 2825);
FORCEPROP 1 LAST MATERIAL CHIP
J 0
(-7450 2775);
DISPLAY 0.489362 (-7450 2775);
PAINT SKYBLUE (-7450 2775);
FORCEPROP 1 LAST TOLERANCE 1%
J 0
(-7450 2875);
DISPLAY 0.489362 (-7450 2875);
PAINT SKYBLUE (-7450 2875);
FORCEPROP 1 LAST VALUE 2.2
J 0
(-7450 2925);
DISPLAY 0.489362 (-7450 2925);
PAINT SKYBLUE (-7450 2925);
FORCEPROP 1 LAST PART_NUMBER CS-2202FB00
J 0
(-7450 2725);
DISPLAY 0.489362 (-7450 2725);
PAINT SKYBLUE (-7450 2725);
FORCEPROP 1 LAST PACK_TYPE 0402LF
J 0
(-7450 2675);
DISPLAY 0.489362 (-7450 2675);
PAINT SKYBLUE (-7450 2675);
FORCEPROP 2 LAST CDS_LIB pure_quanta
J 0
(-7500 2850);
DISPLAY INVISIBLE (-7500 2850);
FORCEPROP 1 LAST PATH I119
J 0
(-7450 3025);
DISPLAY 0.978723 (-7450 3025);
PAINT WHITE (-7450 3025);
DISPLAY INVISIBLE (-7450 3025);
FORCEADD Q_CAP..1
(-7150 2875);
FORCEPROP 1 LAST LOCATION PC322_SOP1_2
J 0
(-7100 2975);
DISPLAY 0.489362 (-7100 2975);
PAINT SKYBLUE (-7100 2975);
FORCEPROP 0 LAST $SEC 1
J 0
(-7100 3025);
DISPLAY 0.680851 (-7100 3025);
PAINT MONO (-7100 3025);
DISPLAY INVISIBLE (-7100 3025);
FORCEPROP 0 LAST CDS_SEC 1
J 0
(-7100 3025);
DISPLAY 1.021277 (-7100 3025);
DISPLAY INVISIBLE (-7100 3025);
FORCEPROP 1 LASTPIN (-7150 2975) $PN 1
J 0
(-7140 2955);
DISPLAY 0.489362 (-7140 2955);
PAINT MONO (-7140 2955);
FORCEPROP 1 LASTPIN (-7150 2775) $PN 2
J 0
(-7140 2755);
DISPLAY 0.489362 (-7140 2755);
PAINT MONO (-7140 2755);
FORCEPROP 1 LAST MATERIAL X6S
J 0
(-7100 2775);
DISPLAY 0.489362 (-7100 2775);
PAINT SKYBLUE (-7100 2775);
FORCEPROP 1 LAST TOLERANCE 10%
J 0
(-7100 2825);
DISPLAY 0.489362 (-7100 2825);
PAINT SKYBLUE (-7100 2825);
FORCEPROP 1 LAST VALUE 2.2UF
J 0
(-7100 2925);
DISPLAY 0.489362 (-7100 2925);
PAINT SKYBLUE (-7100 2925);
FORCEPROP 1 LAST PART_NUMBER CH5222KEB01
J 0
(-7100 2725);
DISPLAY 0.489362 (-7100 2725);
PAINT SKYBLUE (-7100 2725);
FORCEPROP 1 LAST VOLTAGE 10V
J 0
(-7100 2875);
DISPLAY 0.489362 (-7100 2875);
PAINT SKYBLUE (-7100 2875);
FORCEPROP 1 LAST PACK_TYPE C0402
J 0
(-7100 2675);
DISPLAY 0.489362 (-7100 2675);
PAINT SKYBLUE (-7100 2675);
FORCEPROP 2 LAST CDS_LIB pure_quanta
J 0
(-7150 2875);
DISPLAY INVISIBLE (-7150 2875);
FORCEPROP 1 LAST PATH I120
J 0
(-7100 3025);
DISPLAY 0.978723 (-7100 3025);
PAINT WHITE (-7100 3025);
DISPLAY INVISIBLE (-7100 3025);
FORCEADD VCC_CORE..1
(-7500 3250);
FORCEPROP 3 LASTPIN (-7500 3200) SIG_NAME PVDDCR_CPU0_P1_PVCC\g
J 0
(-7490 3210);
DISPLAY 0.659574 (-7490 3210);
PAINT MONO (-7490 3210);
DISPLAY INVISIBLE (-7490 3210);
FORCEPROP 1 LAST HDL_POWER PVDDCR_CPU0_P1_PVCC
J 1
(-7500 3300);
DISPLAY 0.489362 (-7500 3300);
PAINT GREEN (-7500 3300);
FORCEPROP 2 LAST CDS_LIB pure_quanta_power
J 0
(-7500 3250);
DISPLAY INVISIBLE (-7500 3250);
FORCEPROP 1 LAST PATH I121
J 0
(-7450 3275);
DISPLAY 0.872340 (-7450 3275);
PAINT AQUA (-7450 3275);
DISPLAY INVISIBLE (-7450 3275);
FORCEADD OFFPAGE..3
(-2075 1700);
FORCEPROP 2 LAST $XR0 191 
J 0
(-1861 1700);
DISPLAY 0.638298 (-1861 1700);
PAINT MONO (-1861 1700);
FORCEPROP 2 LAST CDS_LIB standard
J 0
(-2075 1700);
DISPLAY INVISIBLE (-2075 1700);
FORCEPROP 1 LAST OFFPAGE TRUE
J 0
(-1750 1575);
DISPLAY 0.872340 (-1750 1575);
PAINT GREEN (-1750 1575);
DISPLAY INVISIBLE (-1750 1575);
FORCEPROP 1 LAST COMMENT_BODY TRUE
J 0
(-2125 1600);
DISPLAY 0.872340 (-2125 1600);
PAINT GREEN (-2125 1600);
DISPLAY INVISIBLE (-2125 1600);
FORCEPROP 2 LAST PATH I122
J 0
(-1875 1775);
DISPLAY 1.021277 (-1875 1775);
DISPLAY INVISIBLE (-1875 1775);
FORCEADD UNIVERSAL_GND..1
(-4675 3800);
FORCEPROP 3 LASTPIN (-4675 3850) SIG_NAME GND\g
J 0
(-4665 3860);
DISPLAY 0.659574 (-4665 3860);
PAINT MONO (-4665 3860);
DISPLAY INVISIBLE (-4665 3860);
FORCEPROP 2 LAST CDS_LIB pure_quanta_power
J 0
(-4675 3800);
DISPLAY INVISIBLE (-4675 3800);
FORCEPROP 1 LAST PATH I123
J 0
(-4600 3800);
DISPLAY 0.872340 (-4600 3800);
PAINT AQUA (-4600 3800);
DISPLAY INVISIBLE (-4600 3800);
FORCEPROP 1 LAST HDL_POWER GND
J 1
(-4650 3725);
DISPLAY 0.872340 (-4650 3725);
PAINT GREEN (-4650 3725);
DISPLAY INVISIBLE (-4650 3725);
FORCEADD Q_RES..2
(-4675 4025);
FORCEPROP 1 LAST LOCATION PR525
J 0
(-4630 4150);
DISPLAY 0.489362 (-4630 4150);
PAINT SKYBLUE (-4630 4150);
FORCEPROP 0 LAST $SEC 1
J 0
(-4625 4200);
DISPLAY 0.680851 (-4625 4200);
PAINT MONO (-4625 4200);
DISPLAY INVISIBLE (-4625 4200);
FORCEPROP 0 LAST CDS_SEC 1
J 0
(-4625 4200);
DISPLAY 1.021277 (-4625 4200);
DISPLAY INVISIBLE (-4625 4200);
FORCEPROP 1 LASTPIN (-4675 4125) $PN 1
J 0
(-4670 4087);
DISPLAY 0.489362 (-4670 4087);
PAINT MONO (-4670 4087);
FORCEPROP 1 LASTPIN (-4675 3925) $PN 2
J 0
(-4670 3935);
DISPLAY 0.489362 (-4670 3935);
PAINT MONO (-4670 3935);
FORCEPROP 1 LAST VALUE 1.5
J 0
(-4630 4100);
DISPLAY 0.489362 (-4630 4100);
PAINT SKYBLUE (-4630 4100);
FORCEPROP 1 LAST WATTAGE 1/8W
J 0
(-4635 4000);
DISPLAY 0.489362 (-4635 4000);
PAINT SKYBLUE (-4635 4000);
FORCEPROP 1 LAST MATERIAL EMPTY
J 0
(-4635 3950);
DISPLAY 0.489362 (-4635 3950);
PAINT RED (-4635 3950);
FORCEPROP 1 LAST TOLERANCE 1%
J 0
(-4630 4050);
DISPLAY 0.489362 (-4630 4050);
PAINT SKYBLUE (-4630 4050);
FORCEPROP 1 LAST PART_NUMBER CS-1504FB00
J 0
(-4635 3900);
DISPLAY 0.489362 (-4635 3900);
PAINT SKYBLUE (-4635 3900);
FORCEPROP 1 LAST PACK_TYPE 0402LF
J 0
(-4635 3850);
DISPLAY 0.489362 (-4635 3850);
PAINT SKYBLUE (-4635 3850);
FORCEPROP 2 LAST CDS_LIB pure_quanta
J 0
(-4675 4025);
DISPLAY INVISIBLE (-4675 4025);
FORCEPROP 1 LAST PATH I124
J 0
(-4625 4200);
DISPLAY 0.978723 (-4625 4200);
PAINT WHITE (-4625 4200);
DISPLAY INVISIBLE (-4625 4200);
FORCEADD Q_CAP..1
(-4675 4525);
FORCEPROP 1 LAST LOCATION PC141
J 0
(-4625 4625);
DISPLAY 0.489362 (-4625 4625);
PAINT SKYBLUE (-4625 4625);
FORCEPROP 0 LAST $SEC 1
J 0
(-4625 4675);
DISPLAY 0.680851 (-4625 4675);
PAINT MONO (-4625 4675);
DISPLAY INVISIBLE (-4625 4675);
FORCEPROP 0 LAST CDS_SEC 1
J 0
(-4625 4675);
DISPLAY 1.021277 (-4625 4675);
DISPLAY INVISIBLE (-4625 4675);
FORCEPROP 1 LASTPIN (-4675 4625) $PN 1
J 0
(-4665 4605);
DISPLAY 0.489362 (-4665 4605);
PAINT MONO (-4665 4605);
FORCEPROP 1 LASTPIN (-4675 4425) $PN 2
J 0
(-4665 4405);
DISPLAY 0.489362 (-4665 4405);
PAINT MONO (-4665 4405);
FORCEPROP 1 LAST VALUE 560PF
J 0
(-4625 4575);
DISPLAY 0.489362 (-4625 4575);
PAINT SKYBLUE (-4625 4575);
FORCEPROP 1 LAST MATERIAL EMPTY
J 0
(-4625 4425);
DISPLAY 0.489362 (-4625 4425);
PAINT RED (-4625 4425);
FORCEPROP 1 LAST TOLERANCE 10%
J 0
(-4625 4475);
DISPLAY 0.489362 (-4625 4475);
PAINT SKYBLUE (-4625 4475);
FORCEPROP 1 LAST PART_NUMBER CH1566K1B09
J 0
(-4625 4375);
DISPLAY 0.489362 (-4625 4375);
PAINT SKYBLUE (-4625 4375);
FORCEPROP 1 LAST VOLTAGE 50V
J 0
(-4625 4525);
DISPLAY 0.489362 (-4625 4525);
PAINT SKYBLUE (-4625 4525);
FORCEPROP 1 LAST PACK_TYPE C0402
J 0
(-4625 4325);
DISPLAY 0.489362 (-4625 4325);
PAINT SKYBLUE (-4625 4325);
FORCEPROP 2 LAST CDS_LIB pure_quanta
J 0
(-4675 4525);
DISPLAY INVISIBLE (-4675 4525);
FORCEPROP 1 LAST PATH I125
J 0
(-4625 4675);
DISPLAY 0.978723 (-4625 4675);
PAINT WHITE (-4625 4675);
DISPLAY INVISIBLE (-4625 4675);
FORCEADD UNIVERSAL_GND..1
(-4600 975);
FORCEPROP 3 LASTPIN (-4600 1025) SIG_NAME GND\g
J 0
(-4590 1035);
DISPLAY 0.659574 (-4590 1035);
PAINT MONO (-4590 1035);
DISPLAY INVISIBLE (-4590 1035);
FORCEPROP 2 LAST CDS_LIB pure_quanta_power
J 0
(-4600 975);
DISPLAY INVISIBLE (-4600 975);
FORCEPROP 1 LAST PATH I126
J 0
(-4525 975);
DISPLAY 0.872340 (-4525 975);
PAINT AQUA (-4525 975);
DISPLAY INVISIBLE (-4525 975);
FORCEPROP 1 LAST HDL_POWER GND
J 1
(-4575 900);
DISPLAY 0.872340 (-4575 900);
PAINT GREEN (-4575 900);
DISPLAY INVISIBLE (-4575 900);
FORCEADD Q_RES..2
(-4600 1200);
FORCEPROP 1 LAST LOCATION PR526
J 0
(-4555 1325);
DISPLAY 0.489362 (-4555 1325);
PAINT SKYBLUE (-4555 1325);
FORCEPROP 0 LAST $SEC 1
J 0
(-4550 1375);
DISPLAY 0.680851 (-4550 1375);
PAINT MONO (-4550 1375);
DISPLAY INVISIBLE (-4550 1375);
FORCEPROP 0 LAST CDS_SEC 1
J 0
(-4550 1375);
DISPLAY 1.021277 (-4550 1375);
DISPLAY INVISIBLE (-4550 1375);
FORCEPROP 1 LASTPIN (-4600 1300) $PN 1
J 0
(-4595 1262);
DISPLAY 0.489362 (-4595 1262);
PAINT MONO (-4595 1262);
FORCEPROP 1 LASTPIN (-4600 1100) $PN 2
J 0
(-4595 1110);
DISPLAY 0.489362 (-4595 1110);
PAINT MONO (-4595 1110);
FORCEPROP 1 LAST WATTAGE 1/8W
J 0
(-4560 1175);
DISPLAY 0.489362 (-4560 1175);
PAINT SKYBLUE (-4560 1175);
FORCEPROP 1 LAST MATERIAL EMPTY
J 0
(-4560 1125);
DISPLAY 0.489362 (-4560 1125);
PAINT RED (-4560 1125);
FORCEPROP 1 LAST TOLERANCE 1%
J 0
(-4555 1225);
DISPLAY 0.489362 (-4555 1225);
PAINT SKYBLUE (-4555 1225);
FORCEPROP 1 LAST VALUE 1.5
J 0
(-4555 1275);
DISPLAY 0.489362 (-4555 1275);
PAINT SKYBLUE (-4555 1275);
FORCEPROP 1 LAST PART_NUMBER CS-1504FB00
J 0
(-4560 1075);
DISPLAY 0.489362 (-4560 1075);
PAINT SKYBLUE (-4560 1075);
FORCEPROP 1 LAST PACK_TYPE 0402LF
J 0
(-4560 1025);
DISPLAY 0.489362 (-4560 1025);
PAINT SKYBLUE (-4560 1025);
FORCEPROP 2 LAST CDS_LIB pure_quanta
J 0
(-4600 1200);
DISPLAY INVISIBLE (-4600 1200);
FORCEPROP 1 LAST PATH I127
J 0
(-4550 1375);
DISPLAY 0.978723 (-4550 1375);
PAINT WHITE (-4550 1375);
DISPLAY INVISIBLE (-4550 1375);
FORCEADD Q_CAP..1
(-4600 1750);
FORCEPROP 1 LAST LOCATION PC149
J 0
(-4550 1850);
DISPLAY 0.489362 (-4550 1850);
PAINT SKYBLUE (-4550 1850);
FORCEPROP 0 LAST $SEC 1
J 0
(-4550 1900);
DISPLAY 0.680851 (-4550 1900);
PAINT MONO (-4550 1900);
DISPLAY INVISIBLE (-4550 1900);
FORCEPROP 0 LAST CDS_SEC 1
J 0
(-4550 1900);
DISPLAY 1.021277 (-4550 1900);
DISPLAY INVISIBLE (-4550 1900);
FORCEPROP 1 LASTPIN (-4600 1850) $PN 1
J 0
(-4590 1830);
DISPLAY 0.489362 (-4590 1830);
PAINT MONO (-4590 1830);
FORCEPROP 1 LASTPIN (-4600 1650) $PN 2
J 0
(-4590 1630);
DISPLAY 0.489362 (-4590 1630);
PAINT MONO (-4590 1630);
FORCEPROP 1 LAST MATERIAL EMPTY
J 0
(-4550 1650);
DISPLAY 0.489362 (-4550 1650);
PAINT RED (-4550 1650);
FORCEPROP 1 LAST TOLERANCE 10%
J 0
(-4550 1700);
DISPLAY 0.489362 (-4550 1700);
PAINT SKYBLUE (-4550 1700);
FORCEPROP 1 LAST VALUE 560PF
J 0
(-4550 1800);
DISPLAY 0.489362 (-4550 1800);
PAINT SKYBLUE (-4550 1800);
FORCEPROP 1 LAST PART_NUMBER CH1566K1B09
J 0
(-4550 1600);
DISPLAY 0.489362 (-4550 1600);
PAINT SKYBLUE (-4550 1600);
FORCEPROP 1 LAST VOLTAGE 50V
J 0
(-4550 1750);
DISPLAY 0.489362 (-4550 1750);
PAINT SKYBLUE (-4550 1750);
FORCEPROP 1 LAST PACK_TYPE C0402
J 0
(-4550 1550);
DISPLAY 0.489362 (-4550 1550);
PAINT SKYBLUE (-4550 1550);
FORCEPROP 2 LAST CDS_LIB pure_quanta
J 0
(-4600 1750);
DISPLAY INVISIBLE (-4600 1750);
FORCEPROP 1 LAST PATH I128
J 0
(-4550 1900);
DISPLAY 0.978723 (-4550 1900);
PAINT WHITE (-4550 1900);
DISPLAY INVISIBLE (-4550 1900);
FORCEADD Q_RES..2
(-850 4525);
FORCEPROP 1 LAST LOCATION PR339
J 0
(-805 4650);
DISPLAY 0.489362 (-805 4650);
PAINT SKYBLUE (-805 4650);
FORCEPROP 0 LAST $SEC 1
J 0
(-800 4675);
DISPLAY 0.680851 (-800 4675);
PAINT MONO (-800 4675);
DISPLAY INVISIBLE (-800 4675);
FORCEPROP 0 LAST CDS_SEC 1
J 0
(-800 4675);
DISPLAY 1.021277 (-800 4675);
DISPLAY INVISIBLE (-800 4675);
FORCEPROP 1 LASTPIN (-850 4625) $PN 1
J 0
(-845 4587);
DISPLAY 0.787234 (-845 4587);
PAINT MONO (-845 4587);
DISPLAY INVISIBLE (-845 4587);
FORCEPROP 1 LASTPIN (-850 4425) $PN 2
J 0
(-845 4435);
DISPLAY 0.787234 (-845 4435);
PAINT MONO (-845 4435);
DISPLAY INVISIBLE (-845 4435);
FORCEPROP 1 LAST WATTAGE 1/16W
J 0
(-810 4500);
DISPLAY 0.489362 (-810 4500);
PAINT SKYBLUE (-810 4500);
FORCEPROP 1 LAST MATERIAL CHIP
J 0
(-810 4450);
DISPLAY 0.489362 (-810 4450);
PAINT SKYBLUE (-810 4450);
FORCEPROP 1 LAST TOLERANCE 1%
J 0
(-805 4550);
DISPLAY 0.489362 (-805 4550);
PAINT SKYBLUE (-805 4550);
FORCEPROP 1 LAST VALUE 1K
J 0
(-805 4600);
DISPLAY 0.489362 (-805 4600);
PAINT SKYBLUE (-805 4600);
FORCEPROP 1 LAST PART_NUMBER TMP_QCS21002FB24
J 0
(-810 4400);
DISPLAY 0.489362 (-810 4400);
PAINT SKYBLUE (-810 4400);
FORCEPROP 1 LAST PACK_TYPE 0402LF
J 0
(-810 4350);
DISPLAY 0.489362 (-810 4350);
PAINT SKYBLUE (-810 4350);
FORCEPROP 2 LAST CDS_LIB pure_quanta
J 0
(-850 4525);
DISPLAY INVISIBLE (-850 4525);
FORCEPROP 1 LAST PATH I129
J 0
(-800 4700);
DISPLAY 0.978723 (-800 4700);
PAINT WHITE (-800 4700);
DISPLAY INVISIBLE (-800 4700);
FORCEADD Q_CAP..1
(-3825 5575);
FORCEPROP 1 LAST LOCATION PC334_1
J 0
(-3775 5675);
DISPLAY 0.489362 (-3775 5675);
PAINT SKYBLUE (-3775 5675);
FORCEPROP 0 LAST $SEC 1
J 0
(-3775 5700);
DISPLAY 0.680851 (-3775 5700);
PAINT MONO (-3775 5700);
DISPLAY INVISIBLE (-3775 5700);
FORCEPROP 0 LAST CDS_SEC 1
J 0
(-3775 5700);
DISPLAY 0.680851 (-3775 5700);
DISPLAY INVISIBLE (-3775 5700);
FORCEPROP 1 LASTPIN (-3825 5675) $PN 1
J 0
(-3815 5655);
DISPLAY 0.787234 (-3815 5655);
PAINT MONO (-3815 5655);
DISPLAY INVISIBLE (-3815 5655);
FORCEPROP 1 LASTPIN (-3825 5475) $PN 2
J 0
(-3815 5455);
DISPLAY 0.787234 (-3815 5455);
PAINT MONO (-3815 5455);
DISPLAY INVISIBLE (-3815 5455);
FORCEPROP 1 LAST PART_NUMBER CH6104KEA00
J 0
(-3775 5425);
DISPLAY 0.489362 (-3775 5425);
PAINT SKYBLUE (-3775 5425);
FORCEPROP 1 LAST TOLERANCE 10%
J 0
(-3775 5525);
DISPLAY 0.489362 (-3775 5525);
PAINT SKYBLUE (-3775 5525);
FORCEPROP 1 LAST VOLTAGE 25V
J 0
(-3775 5575);
DISPLAY 0.489362 (-3775 5575);
PAINT SKYBLUE (-3775 5575);
FORCEPROP 1 LAST VALUE 10UF
J 0
(-3775 5625);
DISPLAY 0.489362 (-3775 5625);
PAINT SKYBLUE (-3775 5625);
FORCEPROP 1 LAST MATERIAL X6S
J 0
(-3775 5475);
DISPLAY 0.489362 (-3775 5475);
PAINT SKYBLUE (-3775 5475);
FORCEPROP 1 LAST PACK_TYPE C0805
J 0
(-3775 5375);
DISPLAY 0.489362 (-3775 5375);
PAINT SKYBLUE (-3775 5375);
FORCEPROP 2 LAST CDS_LIB pure_quanta
J 0
(-3825 5575);
DISPLAY INVISIBLE (-3825 5575);
FORCEPROP 1 LAST PATH I130
J 0
(-3775 5725);
DISPLAY 0.978723 (-3775 5725);
PAINT WHITE (-3775 5725);
DISPLAY INVISIBLE (-3775 5725);
FORCEADD Q_CAP..1
(-3700 2850);
FORCEPROP 1 LAST LOCATION PC335_2
J 0
(-3650 2950);
DISPLAY 0.489362 (-3650 2950);
PAINT SKYBLUE (-3650 2950);
FORCEPROP 0 LAST $SEC 1
J 0
(-3650 2975);
DISPLAY 0.680851 (-3650 2975);
PAINT MONO (-3650 2975);
DISPLAY INVISIBLE (-3650 2975);
FORCEPROP 0 LAST CDS_SEC 1
J 0
(-3650 2975);
DISPLAY 0.680851 (-3650 2975);
DISPLAY INVISIBLE (-3650 2975);
FORCEPROP 1 LASTPIN (-3700 2950) $PN 1
J 0
(-3690 2930);
DISPLAY 0.787234 (-3690 2930);
PAINT MONO (-3690 2930);
DISPLAY INVISIBLE (-3690 2930);
FORCEPROP 1 LASTPIN (-3700 2750) $PN 2
J 0
(-3690 2730);
DISPLAY 0.787234 (-3690 2730);
PAINT MONO (-3690 2730);
DISPLAY INVISIBLE (-3690 2730);
FORCEPROP 1 LAST PART_NUMBER CH6104KEA00
J 0
(-3650 2700);
DISPLAY 0.489362 (-3650 2700);
PAINT SKYBLUE (-3650 2700);
FORCEPROP 1 LAST MATERIAL X6S
J 0
(-3650 2750);
DISPLAY 0.489362 (-3650 2750);
PAINT SKYBLUE (-3650 2750);
FORCEPROP 1 LAST TOLERANCE 10%
J 0
(-3650 2800);
DISPLAY 0.489362 (-3650 2800);
PAINT SKYBLUE (-3650 2800);
FORCEPROP 1 LAST VALUE 10UF
J 0
(-3650 2900);
DISPLAY 0.489362 (-3650 2900);
PAINT SKYBLUE (-3650 2900);
FORCEPROP 1 LAST VOLTAGE 25V
J 0
(-3650 2850);
DISPLAY 0.489362 (-3650 2850);
PAINT SKYBLUE (-3650 2850);
FORCEPROP 1 LAST PACK_TYPE C0805
J 0
(-3650 2650);
DISPLAY 0.489362 (-3650 2650);
PAINT SKYBLUE (-3650 2650);
FORCEPROP 2 LAST CDS_LIB pure_quanta
J 0
(-3700 2850);
DISPLAY INVISIBLE (-3700 2850);
FORCEPROP 1 LAST PATH I131
J 0
(-3650 3000);
DISPLAY 0.978723 (-3650 3000);
PAINT WHITE (-3650 3000);
DISPLAY INVISIBLE (-3650 3000);
FORCEADD OFFPAGE..3
R 2
(-4125 4475);
FORCEPROP 2 LAST $XR0 191 
J 0
(-4405 4475);
DISPLAY 0.638298 (-4405 4475);
PAINT MONO (-4405 4475);
FORCEPROP 1 LAST COMMENT_BODY TRUE
J 2
(-4075 4375);
DISPLAY 0.872340 (-4075 4375);
PAINT GREEN (-4075 4375);
DISPLAY INVISIBLE (-4075 4375);
FORCEPROP 1 LAST OFFPAGE TRUE
J 2
(-4450 4350);
DISPLAY 0.872340 (-4450 4350);
PAINT GREEN (-4450 4350);
DISPLAY INVISIBLE (-4450 4350);
FORCEPROP 2 LAST CDS_LIB standard
J 2
(-4125 4475);
DISPLAY INVISIBLE (-4125 4475);
FORCEPROP 2 LAST PATH I132
J 0
(-4400 4525);
DISPLAY 1.021277 (-4400 4525);
DISPLAY INVISIBLE (-4400 4525);
FORCEADD UNIVERSAL_GND..1
(-2300 4350);
FORCEPROP 3 LASTPIN (-2300 4400) SIG_NAME GND\g
J 0
(-2290 4410);
DISPLAY 0.659574 (-2290 4410);
PAINT MONO (-2290 4410);
DISPLAY INVISIBLE (-2290 4410);
FORCEPROP 2 LAST CDS_LIB pure_quanta_power
J 0
(-2300 4350);
DISPLAY INVISIBLE (-2300 4350);
FORCEPROP 1 LAST PATH I133
J 0
(-2225 4350);
DISPLAY 0.872340 (-2225 4350);
PAINT AQUA (-2225 4350);
DISPLAY INVISIBLE (-2225 4350);
FORCEPROP 1 LAST HDL_POWER GND
J 1
(-2275 4275);
DISPLAY 0.872340 (-2275 4275);
PAINT GREEN (-2275 4275);
DISPLAY INVISIBLE (-2275 4275);
FORCEADD Q_RES..1
(-7175 4425);
FORCEPROP 1 LAST LOCATION PR207
J 0
(-7200 4475);
DISPLAY 0.489362 (-7200 4475);
PAINT SKYBLUE (-7200 4475);
FORCEPROP 0 LAST $SEC 1
J 0
(-7175 4500);
DISPLAY 0.680851 (-7175 4500);
PAINT MONO (-7175 4500);
DISPLAY INVISIBLE (-7175 4500);
FORCEPROP 0 LAST CDS_SEC 1
J 0
(-7175 4500);
DISPLAY 1.021277 (-7175 4500);
DISPLAY INVISIBLE (-7175 4500);
FORCEPROP 1 LASTPIN (-7275 4425) $PN 1
J 0
(-7263 4437);
DISPLAY 0.489362 (-7263 4437);
PAINT MONO (-7263 4437);
FORCEPROP 1 LASTPIN (-7075 4425) $PN 2
J 0
(-7113 4437);
DISPLAY 0.489362 (-7113 4437);
PAINT MONO (-7113 4437);
FORCEPROP 1 LAST WATTAGE 1/16W
J 0
(-7075 4325);
DISPLAY 0.489362 (-7075 4325);
PAINT SKYBLUE (-7075 4325);
FORCEPROP 1 LAST MATERIAL EMPTY
J 0
(-7475 4325);
DISPLAY 0.489362 (-7475 4325);
PAINT RED (-7475 4325);
FORCEPROP 1 LAST TOLERANCE 1%
J 0
(-7050 4450);
DISPLAY 0.489362 (-7050 4450);
PAINT SKYBLUE (-7050 4450);
FORCEPROP 1 LAST VALUE 8.87K
J 2
(-7300 4450);
DISPLAY 0.489362 (-7300 4450);
PAINT SKYBLUE (-7300 4450);
FORCEPROP 1 LAST PART_NUMBER CS28872FB01
J 0
(-7475 4375);
DISPLAY 0.489362 (-7475 4375);
PAINT SKYBLUE (-7475 4375);
FORCEPROP 1 LAST PACK_TYPE 0402LF
J 0
(-7075 4375);
DISPLAY 0.489362 (-7075 4375);
PAINT SKYBLUE (-7075 4375);
FORCEPROP 2 LAST CDS_LIB pure_quanta
J 0
(-7175 4425);
DISPLAY INVISIBLE (-7175 4425);
FORCEPROP 1 LAST PATH I15
J 0
(-7225 4575);
DISPLAY 0.978723 (-7225 4575);
PAINT WHITE (-7225 4575);
DISPLAY INVISIBLE (-7225 4575);
FORCEADD Q_RES..1
(-4775 5075);
FORCEPROP 1 LAST LOCATION PR209
J 0
(-4800 5125);
DISPLAY 0.489362 (-4800 5125);
PAINT SKYBLUE (-4800 5125);
FORCEPROP 0 LAST $SEC 1
J 0
(-4750 5150);
DISPLAY 0.680851 (-4750 5150);
PAINT MONO (-4750 5150);
DISPLAY INVISIBLE (-4750 5150);
FORCEPROP 0 LAST CDS_SEC 1
J 0
(-4750 5150);
DISPLAY 1.021277 (-4750 5150);
DISPLAY INVISIBLE (-4750 5150);
FORCEPROP 1 LASTPIN (-4875 5075) $PN 1
J 0
(-4863 5087);
DISPLAY 0.489362 (-4863 5087);
PAINT MONO (-4863 5087);
FORCEPROP 1 LASTPIN (-4675 5075) $PN 2
J 0
(-4713 5087);
DISPLAY 0.489362 (-4713 5087);
PAINT MONO (-4713 5087);
FORCEPROP 1 LAST PACK_TYPE 0402LF
J 0
(-4675 4975);
DISPLAY 0.489362 (-4675 4975);
PAINT SKYBLUE (-4675 4975);
FORCEPROP 1 LAST TOLERANCE 1%
J 0
(-4675 5100);
DISPLAY 0.489362 (-4675 5100);
PAINT SKYBLUE (-4675 5100);
FORCEPROP 1 LAST MATERIAL CHIP
J 0
(-5025 4975);
DISPLAY 0.489362 (-5025 4975);
PAINT SKYBLUE (-5025 4975);
FORCEPROP 1 LAST WATTAGE 1/16W
J 0
(-4675 5025);
DISPLAY 0.489362 (-4675 5025);
PAINT SKYBLUE (-4675 5025);
FORCEPROP 1 LAST VALUE 4.7
J 2
(-4875 5100);
DISPLAY 0.489362 (-4875 5100);
PAINT SKYBLUE (-4875 5100);
FORCEPROP 1 LAST PART_NUMBER CS-4702FB19
J 0
(-5025 5025);
DISPLAY 0.489362 (-5025 5025);
PAINT SKYBLUE (-5025 5025);
FORCEPROP 1 LAST PATH I19
J 0
(-4825 5225);
DISPLAY 0.978723 (-4825 5225);
PAINT WHITE (-4825 5225);
DISPLAY INVISIBLE (-4825 5225);
FORCEPROP 2 LAST CDS_LIB pure_quanta
J 0
(-4775 5075);
DISPLAY INVISIBLE (-4775 5075);
FORCEADD UNIVERSAL_GND..1
(-5450 4000);
FORCEPROP 3 LASTPIN (-5450 4050) SIG_NAME GND\g
J 0
(-5440 4060);
DISPLAY 0.659574 (-5440 4060);
PAINT MONO (-5440 4060);
DISPLAY INVISIBLE (-5440 4060);
FORCEPROP 2 LAST CDS_LIB pure_quanta_power
J 0
(-5450 4000);
DISPLAY INVISIBLE (-5450 4000);
FORCEPROP 1 LAST PATH I2
J 0
(-5375 4000);
DISPLAY 0.872340 (-5375 4000);
PAINT AQUA (-5375 4000);
DISPLAY INVISIBLE (-5375 4000);
FORCEPROP 1 LAST HDL_POWER GND
J 1
(-5425 3925);
DISPLAY 0.872340 (-5425 3925);
PAINT GREEN (-5425 3925);
DISPLAY INVISIBLE (-5425 3925);
FORCEADD Q_RES..1
(-4200 3700);
FORCEPROP 1 LAST LOCATION PR211
J 0
(-4250 3750);
DISPLAY 0.489362 (-4250 3750);
PAINT SKYBLUE (-4250 3750);
FORCEPROP 0 LAST $SEC 1
J 0
(-4200 3775);
DISPLAY 0.680851 (-4200 3775);
PAINT MONO (-4200 3775);
DISPLAY INVISIBLE (-4200 3775);
FORCEPROP 0 LAST CDS_SEC 1
J 0
(-4200 3775);
DISPLAY 1.021277 (-4200 3775);
DISPLAY INVISIBLE (-4200 3775);
FORCEPROP 1 LASTPIN (-4300 3700) $PN 1
J 0
(-4288 3712);
DISPLAY 0.489362 (-4288 3712);
PAINT MONO (-4288 3712);
FORCEPROP 1 LASTPIN (-4100 3700) $PN 2
J 0
(-4138 3712);
DISPLAY 0.489362 (-4138 3712);
PAINT MONO (-4138 3712);
FORCEPROP 1 LAST VALUE 0
J 2
(-4325 3725);
DISPLAY 0.489362 (-4325 3725);
PAINT SKYBLUE (-4325 3725);
FORCEPROP 1 LAST PART_NUMBER CS00002JB38
J 0
(-4450 3650);
DISPLAY 0.489362 (-4450 3650);
PAINT SKYBLUE (-4450 3650);
FORCEPROP 1 LAST WATTAGE 1/16W
J 0
(-4100 3650);
DISPLAY 0.489362 (-4100 3650);
PAINT SKYBLUE (-4100 3650);
FORCEPROP 1 LAST MATERIAL CHIP
J 0
(-4450 3600);
DISPLAY 0.489362 (-4450 3600);
PAINT SKYBLUE (-4450 3600);
FORCEPROP 1 LAST TOLERANCE 5%
J 0
(-4075 3725);
DISPLAY 0.489362 (-4075 3725);
PAINT SKYBLUE (-4075 3725);
FORCEPROP 1 LAST PACK_TYPE 0402LF
J 0
(-4100 3600);
DISPLAY 0.489362 (-4100 3600);
PAINT SKYBLUE (-4100 3600);
FORCEPROP 2 LAST CDS_LIB pure_quanta
J 0
(-4200 3700);
DISPLAY INVISIBLE (-4200 3700);
FORCEPROP 1 LAST PATH I22
J 0
(-4250 3850);
DISPLAY 0.978723 (-4250 3850);
PAINT WHITE (-4250 3850);
DISPLAY INVISIBLE (-4250 3850);
FORCEADD Q_CAP..1
(-5100 5575);
FORCEPROP 1 LAST LOCATION PC325_1
J 0
(-5050 5675);
DISPLAY 0.489362 (-5050 5675);
PAINT SKYBLUE (-5050 5675);
FORCEPROP 0 LAST $SEC 1
J 0
(-5050 5700);
DISPLAY 0.680851 (-5050 5700);
PAINT MONO (-5050 5700);
DISPLAY INVISIBLE (-5050 5700);
FORCEPROP 0 LAST CDS_SEC 1
J 0
(-5050 5700);
DISPLAY 1.021277 (-5050 5700);
DISPLAY INVISIBLE (-5050 5700);
FORCEPROP 1 LASTPIN (-5100 5675) $PN 1
J 0
(-5090 5655);
DISPLAY 0.489362 (-5090 5655);
PAINT MONO (-5090 5655);
FORCEPROP 1 LASTPIN (-5100 5475) $PN 2
J 0
(-5090 5455);
DISPLAY 0.489362 (-5090 5455);
PAINT MONO (-5090 5455);
FORCEPROP 1 LAST MATERIAL X6S
J 0
(-5050 5475);
DISPLAY 0.489362 (-5050 5475);
PAINT SKYBLUE (-5050 5475);
FORCEPROP 1 LAST TOLERANCE 10%
J 0
(-5050 5525);
DISPLAY 0.489362 (-5050 5525);
PAINT SKYBLUE (-5050 5525);
FORCEPROP 1 LAST VALUE 1UF
J 0
(-5050 5625);
DISPLAY 0.489362 (-5050 5625);
PAINT SKYBLUE (-5050 5625);
FORCEPROP 1 LAST PART_NUMBER CH5104KEB02
J 0
(-5050 5425);
DISPLAY 0.489362 (-5050 5425);
PAINT SKYBLUE (-5050 5425);
FORCEPROP 1 LAST VOLTAGE 25V
J 0
(-5050 5575);
DISPLAY 0.489362 (-5050 5575);
PAINT SKYBLUE (-5050 5575);
FORCEPROP 1 LAST PACK_TYPE C0402
J 0
(-5050 5375);
DISPLAY 0.489362 (-5050 5375);
PAINT SKYBLUE (-5050 5375);
FORCEPROP 2 LAST CDS_LIB pure_quanta
J 0
(-5100 5575);
DISPLAY INVISIBLE (-5100 5575);
FORCEPROP 1 LAST PATH I23
J 0
(-5050 5725);
DISPLAY 0.978723 (-5050 5725);
PAINT WHITE (-5050 5725);
DISPLAY INVISIBLE (-5050 5725);
FORCEADD Q_CAP..1
(-4775 5575);
FORCEPROP 1 LAST LOCATION PC327_1
J 0
(-4725 5675);
DISPLAY 0.489362 (-4725 5675);
PAINT SKYBLUE (-4725 5675);
FORCEPROP 0 LAST $SEC 1
J 0
(-4725 5700);
DISPLAY 0.680851 (-4725 5700);
PAINT MONO (-4725 5700);
DISPLAY INVISIBLE (-4725 5700);
FORCEPROP 0 LAST CDS_SEC 1
J 0
(-4725 5700);
DISPLAY 1.021277 (-4725 5700);
DISPLAY INVISIBLE (-4725 5700);
FORCEPROP 1 LASTPIN (-4775 5675) $PN 1
J 0
(-4765 5655);
DISPLAY 0.489362 (-4765 5655);
PAINT MONO (-4765 5655);
FORCEPROP 1 LASTPIN (-4775 5475) $PN 2
J 0
(-4765 5455);
DISPLAY 0.489362 (-4765 5455);
PAINT MONO (-4765 5455);
FORCEPROP 1 LAST MATERIAL X6S
J 0
(-4725 5475);
DISPLAY 0.489362 (-4725 5475);
PAINT SKYBLUE (-4725 5475);
FORCEPROP 1 LAST TOLERANCE 10%
J 0
(-4725 5525);
DISPLAY 0.489362 (-4725 5525);
PAINT SKYBLUE (-4725 5525);
FORCEPROP 1 LAST VALUE 10UF
J 0
(-4725 5625);
DISPLAY 0.489362 (-4725 5625);
PAINT SKYBLUE (-4725 5625);
FORCEPROP 1 LAST PART_NUMBER CH6104KEA00
J 0
(-4725 5425);
DISPLAY 0.489362 (-4725 5425);
PAINT SKYBLUE (-4725 5425);
FORCEPROP 1 LAST VOLTAGE 25V
J 0
(-4725 5575);
DISPLAY 0.489362 (-4725 5575);
PAINT SKYBLUE (-4725 5575);
FORCEPROP 1 LAST PACK_TYPE C0805
J 0
(-4725 5375);
DISPLAY 0.489362 (-4725 5375);
PAINT SKYBLUE (-4725 5375);
FORCEPROP 2 LAST CDS_LIB pure_quanta
J 0
(-4775 5575);
DISPLAY INVISIBLE (-4775 5575);
FORCEPROP 1 LAST PATH I24
J 0
(-4725 5725);
DISPLAY 0.978723 (-4725 5725);
PAINT WHITE (-4725 5725);
DISPLAY INVISIBLE (-4725 5725);
FORCEADD Q_CAP..1
(-4450 5575);
FORCEPROP 1 LAST LOCATION PC329_1
J 0
(-4400 5675);
DISPLAY 0.489362 (-4400 5675);
PAINT SKYBLUE (-4400 5675);
FORCEPROP 0 LAST $SEC 1
J 0
(-4400 5700);
DISPLAY 0.680851 (-4400 5700);
PAINT MONO (-4400 5700);
DISPLAY INVISIBLE (-4400 5700);
FORCEPROP 0 LAST CDS_SEC 1
J 0
(-4400 5700);
DISPLAY 1.021277 (-4400 5700);
DISPLAY INVISIBLE (-4400 5700);
FORCEPROP 1 LASTPIN (-4450 5675) $PN 1
J 0
(-4440 5655);
DISPLAY 0.489362 (-4440 5655);
PAINT MONO (-4440 5655);
FORCEPROP 1 LASTPIN (-4450 5475) $PN 2
J 0
(-4440 5455);
DISPLAY 0.489362 (-4440 5455);
PAINT MONO (-4440 5455);
FORCEPROP 1 LAST MATERIAL X6S
J 0
(-4400 5475);
DISPLAY 0.489362 (-4400 5475);
PAINT SKYBLUE (-4400 5475);
FORCEPROP 1 LAST TOLERANCE 10%
J 0
(-4400 5525);
DISPLAY 0.489362 (-4400 5525);
PAINT SKYBLUE (-4400 5525);
FORCEPROP 1 LAST VALUE 10UF
J 0
(-4400 5625);
DISPLAY 0.489362 (-4400 5625);
PAINT SKYBLUE (-4400 5625);
FORCEPROP 1 LAST PART_NUMBER CH6104KEA00
J 0
(-4400 5425);
DISPLAY 0.489362 (-4400 5425);
PAINT SKYBLUE (-4400 5425);
FORCEPROP 1 LAST VOLTAGE 25V
J 0
(-4400 5575);
DISPLAY 0.489362 (-4400 5575);
PAINT SKYBLUE (-4400 5575);
FORCEPROP 1 LAST PACK_TYPE C0805
J 0
(-4400 5375);
DISPLAY 0.489362 (-4400 5375);
PAINT SKYBLUE (-4400 5375);
FORCEPROP 2 LAST CDS_LIB pure_quanta
J 0
(-4450 5575);
DISPLAY INVISIBLE (-4450 5575);
FORCEPROP 1 LAST PATH I25
J 0
(-4400 5725);
DISPLAY 0.978723 (-4400 5725);
PAINT WHITE (-4400 5725);
DISPLAY INVISIBLE (-4400 5725);
FORCEADD Q_CAP..1
(-4150 5575);
FORCEPROP 1 LAST LOCATION PC331_1
J 0
(-4100 5675);
DISPLAY 0.489362 (-4100 5675);
PAINT SKYBLUE (-4100 5675);
FORCEPROP 0 LAST $SEC 1
J 0
(-4100 5700);
DISPLAY 0.680851 (-4100 5700);
PAINT MONO (-4100 5700);
DISPLAY INVISIBLE (-4100 5700);
FORCEPROP 0 LAST CDS_SEC 1
J 0
(-4100 5700);
DISPLAY 1.021277 (-4100 5700);
DISPLAY INVISIBLE (-4100 5700);
FORCEPROP 1 LASTPIN (-4150 5675) $PN 1
J 0
(-4140 5655);
DISPLAY 0.489362 (-4140 5655);
PAINT MONO (-4140 5655);
FORCEPROP 1 LASTPIN (-4150 5475) $PN 2
J 0
(-4140 5455);
DISPLAY 0.489362 (-4140 5455);
PAINT MONO (-4140 5455);
FORCEPROP 1 LAST MATERIAL X6S
J 0
(-4100 5475);
DISPLAY 0.489362 (-4100 5475);
PAINT SKYBLUE (-4100 5475);
FORCEPROP 1 LAST TOLERANCE 10%
J 0
(-4100 5525);
DISPLAY 0.489362 (-4100 5525);
PAINT SKYBLUE (-4100 5525);
FORCEPROP 1 LAST VALUE 10UF
J 0
(-4100 5625);
DISPLAY 0.489362 (-4100 5625);
PAINT SKYBLUE (-4100 5625);
FORCEPROP 1 LAST PART_NUMBER CH6104KEA00
J 0
(-4100 5425);
DISPLAY 0.489362 (-4100 5425);
PAINT SKYBLUE (-4100 5425);
FORCEPROP 1 LAST VOLTAGE 25V
J 0
(-4100 5575);
DISPLAY 0.489362 (-4100 5575);
PAINT SKYBLUE (-4100 5575);
FORCEPROP 1 LAST PACK_TYPE C0805
J 0
(-4100 5375);
DISPLAY 0.489362 (-4100 5375);
PAINT SKYBLUE (-4100 5375);
FORCEPROP 2 LAST CDS_LIB pure_quanta
J 0
(-4150 5575);
DISPLAY INVISIBLE (-4150 5575);
FORCEPROP 1 LAST PATH I26
J 0
(-4100 5725);
DISPLAY 0.978723 (-4100 5725);
PAINT WHITE (-4100 5725);
DISPLAY INVISIBLE (-4100 5725);
FORCEADD Q_CAP..1
(-1950 4525);
FORCEPROP 1 LAST LOCATION PC338
J 0
(-1875 4650);
DISPLAY 0.489362 (-1875 4650);
PAINT SKYBLUE (-1875 4650);
FORCEPROP 0 LAST $SEC 1
J 0
(-1900 4650);
DISPLAY 0.680851 (-1900 4650);
PAINT MONO (-1900 4650);
DISPLAY INVISIBLE (-1900 4650);
FORCEPROP 0 LAST CDS_SEC 1
J 0
(-1900 4650);
DISPLAY 1.021277 (-1900 4650);
DISPLAY INVISIBLE (-1900 4650);
FORCEPROP 1 LASTPIN (-1950 4625) $PN 1
J 0
(-1940 4605);
DISPLAY 0.489362 (-1940 4605);
PAINT MONO (-1940 4605);
FORCEPROP 1 LASTPIN (-1950 4425) $PN 2
J 0
(-1940 4405);
DISPLAY 0.489362 (-1940 4405);
PAINT MONO (-1940 4405);
FORCEPROP 1 LAST MATERIAL X7R
J 0
(-1875 4450);
DISPLAY 0.489362 (-1875 4450);
PAINT SKYBLUE (-1875 4450);
FORCEPROP 1 LAST TOLERANCE 10%
J 0
(-1875 4500);
DISPLAY 0.489362 (-1875 4500);
PAINT SKYBLUE (-1875 4500);
FORCEPROP 1 LAST VALUE 0.1UF
J 0
(-1875 4600);
DISPLAY 0.489362 (-1875 4600);
PAINT SKYBLUE (-1875 4600);
FORCEPROP 1 LAST PART_NUMBER CH4104K1B00
J 0
(-1875 4400);
DISPLAY 0.489362 (-1875 4400);
PAINT SKYBLUE (-1875 4400);
FORCEPROP 1 LAST VOLTAGE 25V
J 0
(-1875 4550);
DISPLAY 0.489362 (-1875 4550);
PAINT SKYBLUE (-1875 4550);
FORCEPROP 1 LAST PACK_TYPE 0402
J 0
(-1875 4350);
DISPLAY 0.489362 (-1875 4350);
PAINT SKYBLUE (-1875 4350);
FORCEPROP 2 LAST CDS_LIB pure_quanta
J 0
(-1950 4525);
DISPLAY INVISIBLE (-1950 4525);
FORCEPROP 1 LAST PATH I29
J 0
(-1900 4675);
DISPLAY 0.978723 (-1900 4675);
PAINT WHITE (-1900 4675);
DISPLAY INVISIBLE (-1900 4675);
FORCEADD OFFPAGE..1
(-8075 4625);
FORCEPROP 2 LAST $XR5 192 
J 0
(-8927 4625);
DISPLAY 0.638298 (-8927 4625);
PAINT MONO (-8927 4625);
FORCEPROP 2 LAST $XR4 191 
J 0
(-8807 4625);
DISPLAY 0.638298 (-8807 4625);
PAINT MONO (-8807 4625);
FORCEPROP 2 LAST $XR3 189 
J 0
(-8687 4625);
DISPLAY 0.638298 (-8687 4625);
PAINT MONO (-8687 4625);
FORCEPROP 2 LAST $XR2 188 
J 0
(-8567 4625);
DISPLAY 0.638298 (-8567 4625);
PAINT MONO (-8567 4625);
FORCEPROP 2 LAST $XR1 187 
J 0
(-8447 4625);
DISPLAY 0.638298 (-8447 4625);
PAINT MONO (-8447 4625);
FORCEPROP 2 LAST $XR0 186 
J 0
(-8327 4625);
DISPLAY 0.638298 (-8327 4625);
PAINT MONO (-8327 4625);
FORCEPROP 2 LAST CDS_LIB standard
J 0
(-8075 4625);
DISPLAY INVISIBLE (-8075 4625);
FORCEPROP 1 LAST OFFPAGE TRUE
J 0
(-7750 4500);
DISPLAY 0.872340 (-7750 4500);
PAINT GREEN (-7750 4500);
DISPLAY INVISIBLE (-7750 4500);
FORCEPROP 1 LAST COMMENT_BODY TRUE
J 0
(-7950 4525);
DISPLAY 0.872340 (-7950 4525);
PAINT GREEN (-7950 4525);
DISPLAY INVISIBLE (-7950 4525);
FORCEPROP 2 LAST PATH I3
J 0
(-8025 4700);
DISPLAY 1.021277 (-8025 4700);
DISPLAY INVISIBLE (-8025 4700);
FORCEADD UNIVERSAL_GND..1
(-3900 5250);
FORCEPROP 3 LASTPIN (-3900 5300) SIG_NAME GND\g
J 0
(-3890 5310);
DISPLAY 0.659574 (-3890 5310);
PAINT MONO (-3890 5310);
DISPLAY INVISIBLE (-3890 5310);
FORCEPROP 2 LAST CDS_LIB pure_quanta_power
J 0
(-3900 5250);
DISPLAY INVISIBLE (-3900 5250);
FORCEPROP 1 LAST PATH I31
J 0
(-3825 5250);
DISPLAY 0.872340 (-3825 5250);
PAINT AQUA (-3825 5250);
DISPLAY INVISIBLE (-3825 5250);
FORCEPROP 1 LAST HDL_POWER GND
J 1
(-3875 5175);
DISPLAY 0.872340 (-3875 5175);
PAINT GREEN (-3875 5175);
DISPLAY INVISIBLE (-3875 5175);
FORCEADD Q_INDUCTOR..1
(-3050 5775);
FORCEPROP 1 LAST LOCATION PL37
J 0
(-3175 5935);
DISPLAY 0.489362 (-3175 5935);
PAINT SKYBLUE (-3175 5935);
FORCEPROP 0 LAST $SEC 1
J 0
(-3175 6050);
DISPLAY 0.680851 (-3175 6050);
PAINT MONO (-3175 6050);
DISPLAY INVISIBLE (-3175 6050);
FORCEPROP 0 LAST CDS_SEC 1
J 0
(-3175 6050);
DISPLAY 1.021277 (-3175 6050);
DISPLAY INVISIBLE (-3175 6050);
FORCEPROP 0 LASTPIN (-3150 5750) $PN 1
J 2
(-3160 5760);
DISPLAY 0.489362 (-3160 5760);
PAINT MONO (-3160 5760);
FORCEPROP 0 LASTPIN (-2950 5750) $PN 2
J 0
(-2940 5760);
DISPLAY 0.489362 (-2940 5760);
PAINT MONO (-2940 5760);
FORCEPROP 1 LAST MATERIAL IND
J 0
(-3175 5830);
DISPLAY 0.489362 (-3175 5830);
PAINT SKYBLUE (-3175 5830);
FORCEPROP 2 LAST VALUE 50NH/86A
J 0
(-3175 6025);
DISPLAY 0.489362 (-3175 6025);
PAINT SKYBLUE (-3175 6025);
FORCEPROP 1 LAST PART_NUMBER CVA50^0MZ09
J 0
(-3175 5885);
DISPLAY 0.489362 (-3175 5885);
PAINT SKYBLUE (-3175 5885);
FORCEPROP 2 LAST PACK_TYPE SMLF
J 0
(-3175 5975);
DISPLAY 0.489362 (-3175 5975);
PAINT SKYBLUE (-3175 5975);
FORCEPROP 1 LAST NEEDS_NO_SIZE TRUE
J 0
(-3050 5775);
DISPLAY 0.468085 (-3050 5775);
PAINT GREEN (-3050 5775);
DISPLAY INVISIBLE (-3050 5775);
FORCEPROP 2 LAST CDS_LIB pure_quanta
J 0
(-3050 5775);
DISPLAY INVISIBLE (-3050 5775);
FORCEPROP 1 LAST PATH I34
J 0
(-2975 5830);
DISPLAY 0.723404 (-2975 5830);
PAINT GREEN (-2975 5830);
DISPLAY INVISIBLE (-2975 5830);
FORCEADD VCC_CORE..1
(-2775 5850);
FORCEPROP 3 LASTPIN (-2775 5800) SIG_NAME P12V_STBY\g
J 0
(-2765 5810);
DISPLAY 0.659574 (-2765 5810);
PAINT MONO (-2765 5810);
DISPLAY INVISIBLE (-2765 5810);
FORCEPROP 1 LAST HDL_POWER P12V_STBY
J 1
(-2775 5900);
DISPLAY 0.489362 (-2775 5900);
PAINT GREEN (-2775 5900);
FORCEPROP 2 LAST CDS_LIB pure_quanta_power
J 0
(-2775 5850);
DISPLAY INVISIBLE (-2775 5850);
FORCEPROP 1 LAST PATH I35
J 0
(-2725 5875);
DISPLAY 0.872340 (-2725 5875);
PAINT AQUA (-2725 5875);
DISPLAY INVISIBLE (-2725 5875);
FORCEADD Q_CAP..1
(-1550 4550);
FORCEPROP 1 LAST LOCATION PC341_1
J 0
(-1500 4650);
DISPLAY 0.489362 (-1500 4650);
PAINT SKYBLUE (-1500 4650);
FORCEPROP 0 LAST $SEC 1
J 0
(-1500 4675);
DISPLAY 0.680851 (-1500 4675);
PAINT MONO (-1500 4675);
DISPLAY INVISIBLE (-1500 4675);
FORCEPROP 0 LAST CDS_SEC 1
J 0
(-1500 4675);
DISPLAY 1.021277 (-1500 4675);
DISPLAY INVISIBLE (-1500 4675);
FORCEPROP 1 LASTPIN (-1550 4650) $PN 1
J 0
(-1540 4630);
DISPLAY 0.489362 (-1540 4630);
PAINT MONO (-1540 4630);
FORCEPROP 1 LASTPIN (-1550 4450) $PN 2
J 0
(-1540 4430);
DISPLAY 0.489362 (-1540 4430);
PAINT MONO (-1540 4430);
FORCEPROP 1 LAST MATERIAL X6S
J 0
(-1500 4450);
DISPLAY 0.489362 (-1500 4450);
PAINT SKYBLUE (-1500 4450);
FORCEPROP 1 LAST TOLERANCE 20%
J 0
(-1500 4500);
DISPLAY 0.489362 (-1500 4500);
PAINT SKYBLUE (-1500 4500);
FORCEPROP 1 LAST VALUE 22UF
J 0
(-1500 4600);
DISPLAY 0.489362 (-1500 4600);
PAINT SKYBLUE (-1500 4600);
FORCEPROP 1 LAST PART_NUMBER TMP_QCH622KMEA01
J 0
(-1500 4400);
DISPLAY 0.489362 (-1500 4400);
PAINT SKYBLUE (-1500 4400);
FORCEPROP 1 LAST VOLTAGE 4V
J 0
(-1500 4550);
DISPLAY 0.489362 (-1500 4550);
PAINT SKYBLUE (-1500 4550);
FORCEPROP 1 LAST PACK_TYPE 0805
J 0
(-1500 4350);
DISPLAY 0.489362 (-1500 4350);
PAINT SKYBLUE (-1500 4350);
FORCEPROP 2 LAST CDS_LIB pure_quanta
J 0
(-1550 4550);
DISPLAY INVISIBLE (-1550 4550);
FORCEPROP 1 LAST PATH I37
J 0
(-1500 4700);
DISPLAY 0.978723 (-1500 4700);
PAINT WHITE (-1500 4700);
DISPLAY INVISIBLE (-1500 4700);
FORCEADD UNIVERSAL_GND..1
(-850 4150);
FORCEPROP 3 LASTPIN (-850 4200) SIG_NAME GND\g
J 0
(-840 4210);
DISPLAY 0.659574 (-840 4210);
PAINT MONO (-840 4210);
DISPLAY INVISIBLE (-840 4210);
FORCEPROP 2 LAST CDS_LIB pure_quanta_power
J 0
(-850 4150);
DISPLAY INVISIBLE (-850 4150);
FORCEPROP 1 LAST PATH I38
J 0
(-775 4150);
DISPLAY 0.872340 (-775 4150);
PAINT AQUA (-775 4150);
DISPLAY INVISIBLE (-775 4150);
FORCEPROP 1 LAST HDL_POWER GND
J 1
(-825 4075);
DISPLAY 0.872340 (-825 4075);
PAINT GREEN (-825 4075);
DISPLAY INVISIBLE (-825 4075);
FORCEADD Q_CAP..1
(-1125 4550);
FORCEPROP 1 LAST LOCATION PC344_1
J 0
(-1075 4650);
DISPLAY 0.489362 (-1075 4650);
PAINT SKYBLUE (-1075 4650);
FORCEPROP 0 LAST $SEC 1
J 0
(-1075 4675);
DISPLAY 0.680851 (-1075 4675);
PAINT MONO (-1075 4675);
DISPLAY INVISIBLE (-1075 4675);
FORCEPROP 0 LAST CDS_SEC 1
J 0
(-1075 4675);
DISPLAY 1.021277 (-1075 4675);
DISPLAY INVISIBLE (-1075 4675);
FORCEPROP 1 LASTPIN (-1125 4650) $PN 1
J 0
(-1115 4630);
DISPLAY 0.489362 (-1115 4630);
PAINT MONO (-1115 4630);
FORCEPROP 1 LASTPIN (-1125 4450) $PN 2
J 0
(-1115 4430);
DISPLAY 0.489362 (-1115 4430);
PAINT MONO (-1115 4430);
FORCEPROP 1 LAST MATERIAL X6S
J 0
(-1075 4450);
DISPLAY 0.489362 (-1075 4450);
PAINT SKYBLUE (-1075 4450);
FORCEPROP 1 LAST TOLERANCE 20%
J 0
(-1075 4500);
DISPLAY 0.489362 (-1075 4500);
PAINT SKYBLUE (-1075 4500);
FORCEPROP 1 LAST VALUE 22UF
J 0
(-1075 4600);
DISPLAY 0.489362 (-1075 4600);
PAINT SKYBLUE (-1075 4600);
FORCEPROP 1 LAST VOLTAGE 4V
J 0
(-1075 4550);
DISPLAY 0.489362 (-1075 4550);
PAINT SKYBLUE (-1075 4550);
FORCEPROP 1 LAST PACK_TYPE 0805
J 0
(-1075 4400);
DISPLAY 0.489362 (-1075 4400);
PAINT SKYBLUE (-1075 4400);
FORCEPROP 2 LAST CDS_LIB pure_quanta
J 0
(-1125 4550);
DISPLAY INVISIBLE (-1125 4550);
FORCEPROP 1 LAST PATH I39
J 0
(-1075 4700);
DISPLAY 0.978723 (-1075 4700);
PAINT WHITE (-1075 4700);
DISPLAY INVISIBLE (-1075 4700);
FORCEPROP 1 LAST PART_NUMBER TMP_QCH622KMEA01
J 0
(-1075 4400);
DISPLAY 0.489362 (-1075 4400);
PAINT SKYBLUE (-1075 4400);
DISPLAY INVISIBLE (-1075 4400);
FORCEADD Q_CAP..1
(-7850 4450);
FORCEPROP 1 LAST LOCATION PC317_7
J 0
(-7800 4550);
DISPLAY 0.489362 (-7800 4550);
PAINT SKYBLUE (-7800 4550);
FORCEPROP 0 LAST $SEC 1
J 0
(-7800 4575);
DISPLAY 0.680851 (-7800 4575);
PAINT MONO (-7800 4575);
DISPLAY INVISIBLE (-7800 4575);
FORCEPROP 0 LAST CDS_SEC 1
J 0
(-7800 4575);
DISPLAY 1.021277 (-7800 4575);
DISPLAY INVISIBLE (-7800 4575);
FORCEPROP 1 LASTPIN (-7850 4550) $PN 1
J 0
(-7840 4530);
DISPLAY 0.489362 (-7840 4530);
PAINT MONO (-7840 4530);
FORCEPROP 1 LASTPIN (-7850 4350) $PN 2
J 0
(-7840 4330);
DISPLAY 0.489362 (-7840 4330);
PAINT MONO (-7840 4330);
FORCEPROP 1 LAST MATERIAL X7R
J 0
(-7800 4350);
DISPLAY 0.489362 (-7800 4350);
PAINT SKYBLUE (-7800 4350);
FORCEPROP 1 LAST TOLERANCE 10%
J 0
(-7800 4400);
DISPLAY 0.489362 (-7800 4400);
PAINT SKYBLUE (-7800 4400);
FORCEPROP 1 LAST VALUE 0.1UF
J 0
(-7800 4500);
DISPLAY 0.489362 (-7800 4500);
PAINT SKYBLUE (-7800 4500);
FORCEPROP 1 LAST PART_NUMBER CH4104K1B00
J 0
(-7800 4300);
DISPLAY 0.489362 (-7800 4300);
PAINT SKYBLUE (-7800 4300);
FORCEPROP 1 LAST VOLTAGE 25V
J 0
(-7800 4450);
DISPLAY 0.489362 (-7800 4450);
PAINT SKYBLUE (-7800 4450);
FORCEPROP 1 LAST PACK_TYPE 0402
J 0
(-7800 4250);
DISPLAY 0.489362 (-7800 4250);
PAINT SKYBLUE (-7800 4250);
FORCEPROP 2 LAST CDS_LIB pure_quanta
J 0
(-7850 4450);
DISPLAY INVISIBLE (-7850 4450);
FORCEPROP 1 LAST PATH I4
J 0
(-7800 4600);
DISPLAY 0.978723 (-7800 4600);
PAINT WHITE (-7800 4600);
DISPLAY INVISIBLE (-7800 4600);
FORCEADD VCC_CORE..1
(-850 4850);
FORCEPROP 3 LASTPIN (-850 4800) SIG_NAME PVDDCR_SOC_P1\g
J 0
(-840 4810);
DISPLAY 0.659574 (-840 4810);
PAINT MONO (-840 4810);
DISPLAY INVISIBLE (-840 4810);
FORCEPROP 1 LAST HDL_POWER PVDDCR_SOC_P1
J 1
(-850 4900);
DISPLAY 0.489362 (-850 4900);
PAINT GREEN (-850 4900);
FORCEPROP 2 LAST CDS_LIB pure_quanta_power
J 0
(-850 4850);
DISPLAY INVISIBLE (-850 4850);
FORCEPROP 1 LAST PATH I40
J 0
(-800 4875);
DISPLAY 0.872340 (-800 4875);
PAINT AQUA (-800 4875);
DISPLAY INVISIBLE (-800 4875);
FORCEADD Q_INDUCTOR4P_14..1
(-3175 4600);
FORCEPROP 1 LAST LOCATION PL35
J 0
(-3400 4855);
DISPLAY 0.489362 (-3400 4855);
PAINT SKYBLUE (-3400 4855);
FORCEPROP 0 LAST $SEC 1
J 0
(-3400 5000);
DISPLAY 0.680851 (-3400 5000);
PAINT MONO (-3400 5000);
DISPLAY INVISIBLE (-3400 5000);
FORCEPROP 0 LAST CDS_SEC 1
J 0
(-3400 5000);
DISPLAY 1.021277 (-3400 5000);
DISPLAY INVISIBLE (-3400 5000);
FORCEPROP 0 LASTPIN (-3575 4725) $PN 1
J 2
(-3585 4735);
DISPLAY 0.489362 (-3585 4735);
PAINT MONO (-3585 4735);
FORCEPROP 0 LASTPIN (-3575 4475) $PN 2
J 2
(-3585 4485);
DISPLAY 0.489362 (-3585 4485);
PAINT MONO (-3585 4485);
FORCEPROP 0 LASTPIN (-2775 4475) $PN 3
J 0
(-2765 4485);
DISPLAY 0.489362 (-2765 4485);
PAINT MONO (-2765 4485);
FORCEPROP 0 LASTPIN (-2775 4725) $PN 4
J 0
(-2765 4735);
DISPLAY 0.489362 (-2765 4735);
PAINT MONO (-2765 4735);
FORCEPROP 1 LAST PART_NUMBER CV+15^0TZ04
J 0
(-3400 4760);
DISPLAY 0.489362 (-3400 4760);
PAINT SKYBLUE (-3400 4760);
FORCEPROP 2 LAST PART_TYPE SMLF
J 0
(-3400 4950);
DISPLAY 1.021277 (-3400 4950);
FORCEPROP 1 LAST MATERIAL IND
J 0
(-3400 4810);
DISPLAY 0.489362 (-3400 4810);
PAINT SKYBLUE (-3400 4810);
FORCEPROP 2 LAST VALUE 150NH
J 0
(-3400 4900);
DISPLAY 0.489362 (-3400 4900);
PAINT SKYBLUE (-3400 4900);
FORCEPROP 2 LAST CDS_LIB pure_quanta
J 0
(-3175 4600);
DISPLAY INVISIBLE (-3175 4600);
FORCEPROP 1 LAST NEEDS_NO_SIZE TRUE
J 0
(-3175 4600);
DISPLAY 0.468085 (-3175 4600);
PAINT GREEN (-3175 4600);
DISPLAY INVISIBLE (-3175 4600);
FORCEPROP 1 LAST PATH I42
J 0
(-2975 4755);
DISPLAY 0.723404 (-2975 4755);
PAINT GREEN (-2975 4755);
DISPLAY INVISIBLE (-2975 4755);
FORCEADD Q_CAP..1
(-3925 4950);
FORCEPROP 1 LAST LOCATION PC333
J 0
(-3875 5075);
DISPLAY 0.489362 (-3875 5075);
PAINT SKYBLUE (-3875 5075);
FORCEPROP 0 LAST $SEC 1
J 0
(-3875 5100);
DISPLAY 0.680851 (-3875 5100);
PAINT MONO (-3875 5100);
DISPLAY INVISIBLE (-3875 5100);
FORCEPROP 0 LAST CDS_SEC 1
J 0
(-3875 5100);
DISPLAY 1.021277 (-3875 5100);
DISPLAY INVISIBLE (-3875 5100);
FORCEPROP 1 LASTPIN (-3925 5050) $PN 1
J 0
(-3915 5030);
DISPLAY 0.489362 (-3915 5030);
PAINT MONO (-3915 5030);
FORCEPROP 1 LASTPIN (-3925 4850) $PN 2
J 0
(-3915 4830);
DISPLAY 0.489362 (-3915 4830);
PAINT MONO (-3915 4830);
FORCEPROP 1 LAST MATERIAL X7R
J 0
(-3875 4875);
DISPLAY 0.489362 (-3875 4875);
PAINT SKYBLUE (-3875 4875);
FORCEPROP 1 LAST TOLERANCE 10%
J 0
(-3875 4925);
DISPLAY 0.489362 (-3875 4925);
PAINT SKYBLUE (-3875 4925);
FORCEPROP 1 LAST VALUE 0.22UF
J 0
(-3875 5025);
DISPLAY 0.489362 (-3875 5025);
PAINT SKYBLUE (-3875 5025);
FORCEPROP 1 LAST PART_NUMBER CH4223K1B00
J 0
(-3875 4825);
DISPLAY 0.489362 (-3875 4825);
PAINT SKYBLUE (-3875 4825);
FORCEPROP 1 LAST VOLTAGE 16V
J 0
(-3875 4975);
DISPLAY 0.489362 (-3875 4975);
PAINT SKYBLUE (-3875 4975);
FORCEPROP 1 LAST PACK_TYPE 0402
J 0
(-3875 4775);
DISPLAY 0.489362 (-3875 4775);
PAINT SKYBLUE (-3875 4775);
FORCEPROP 2 LAST CDS_LIB pure_quanta
J 0
(-3925 4950);
DISPLAY INVISIBLE (-3925 4950);
FORCEPROP 1 LAST PATH I43
J 0
(-3875 5100);
DISPLAY 0.978723 (-3875 5100);
PAINT WHITE (-3875 5100);
DISPLAY INVISIBLE (-3875 5100);
FORCEADD ISL99390FRZTR5935..1
(-6025 4725);
FORCEPROP 1 LAST LOCATION PU30
J 0
(-6325 5600);
DISPLAY 0.489362 (-6325 5600);
PAINT SKYBLUE (-6325 5600);
FORCEPROP 2 LAST $SEC 1
J 0
(-6325 5750);
DISPLAY 0.680851 (-6325 5750);
PAINT MONO (-6325 5750);
DISPLAY INVISIBLE (-6325 5750);
FORCEPROP 2 LAST CDS_SEC 1
J 0
(-6325 5750);
DISPLAY 1.021277 (-6325 5750);
DISPLAY INVISIBLE (-6325 5750);
FORCEPROP 2 LASTPIN (-5625 4275) $PN 2
J 0
(-5615 4285);
DISPLAY 0.489362 (-5615 4285);
PAINT MONO (-5615 4285);
FORCEPROP 2 LASTPIN (-5625 5075) $PN 33
J 0
(-5615 5085);
DISPLAY 0.489362 (-5615 5085);
PAINT MONO (-5615 5085);
FORCEPROP 2 LASTPIN (-6475 4475) $PN 31
J 2
(-6485 4485);
DISPLAY 0.489362 (-6485 4485);
PAINT MONO (-6485 4485);
FORCEPROP 2 LASTPIN (-6475 4875) $PN 35
J 2
(-6485 4885);
DISPLAY 0.489362 (-6485 4885);
PAINT MONO (-6485 4885);
FORCEPROP 2 LASTPIN (-5625 4425) $PN 6
J 0
(-5615 4435);
DISPLAY 0.489362 (-5615 4435);
PAINT MONO (-5615 4435);
FORCEPROP 2 LASTPIN (-5625 4375) $PN 41
J 0
(-5615 4385);
DISPLAY 0.489362 (-5615 4385);
PAINT MONO (-5615 4385);
FORCEPROP 2 LASTPIN (-6475 4725) $PN 38
J 2
(-6485 4735);
DISPLAY 0.489362 (-6485 4735);
PAINT MONO (-6485 4735);
FORCEPROP 2 LASTPIN (-6475 4425) $PN 37
J 2
(-6485 4435);
DISPLAY 0.489362 (-6485 4435);
PAINT MONO (-6485 4435);
FORCEPROP 2 LASTPIN (-5625 4225) $PN 5
J 0
(-5615 4235);
DISPLAY 0.489362 (-5615 4235);
PAINT MONO (-5615 4235);
FORCEPROP 2 LASTPIN (-5625 4175) $PN 7_9-20_24
J 0
(-5615 4185);
DISPLAY 0.489362 (-5615 4185);
PAINT MONO (-5615 4185);
FORCEPROP 2 LASTPIN (-5625 4125) $PN 40
J 0
(-5615 4135);
DISPLAY 0.489362 (-5615 4135);
PAINT MONO (-5615 4135);
FORCEPROP 2 LASTPIN (-5625 4825) $PN 32
J 0
(-5615 4835);
DISPLAY 0.489362 (-5615 4835);
PAINT MONO (-5615 4835);
FORCEPROP 2 LASTPIN (-6475 5375) $PN 4
J 2
(-6485 5385);
DISPLAY 0.489362 (-6485 5385);
PAINT MONO (-6485 5385);
FORCEPROP 2 LASTPIN (-6475 4125) $PN 34
J 2
(-6485 4135);
DISPLAY 0.489362 (-6485 4135);
PAINT MONO (-6485 4135);
FORCEPROP 2 LASTPIN (-6475 4625) $PN 39
J 2
(-6485 4635);
DISPLAY 0.489362 (-6485 4635);
PAINT MONO (-6485 4635);
FORCEPROP 2 LASTPIN (-5625 4725) $PN 10_19
J 0
(-5615 4735);
DISPLAY 0.489362 (-5615 4735);
PAINT MONO (-5615 4735);
FORCEPROP 2 LASTPIN (-6475 4225) $PN 36
J 2
(-6485 4235);
DISPLAY 0.489362 (-6485 4235);
PAINT MONO (-6485 4235);
FORCEPROP 2 LASTPIN (-6475 5075) $PN 3
J 2
(-6485 5085);
DISPLAY 0.489362 (-6485 5085);
PAINT MONO (-6485 5085);
FORCEPROP 2 LASTPIN (-5625 5375) $PN 25_29
J 0
(-5615 5385);
DISPLAY 0.489362 (-5615 5385);
PAINT MONO (-5615 5385);
FORCEPROP 2 LASTPIN (-5625 5325) $PN 30
J 0
(-5615 5335);
DISPLAY 0.489362 (-5615 5335);
PAINT MONO (-5615 5335);
FORCEPROP 2 LASTPIN (-5625 4475) $PN 1
J 0
(-5615 4485);
DISPLAY 0.489362 (-5615 4485);
PAINT MONO (-5615 4485);
FORCEPROP 2 LAST PART_TYPE SMLF
J 0
(-6325 5700);
DISPLAY 1.021277 (-6325 5700);
FORCEPROP 1 LAST MATERIAL IC
J 0
(-6325 5450);
DISPLAY 0.489362 (-6325 5450);
PAINT SKYBLUE (-6325 5450);
FORCEPROP 2 LAST VALUE ISL99390FRZ-TR5935
J 0
(-6325 5650);
DISPLAY 0.489362 (-6325 5650);
PAINT SKYBLUE (-6325 5650);
FORCEPROP 1 LAST PART_NUMBER AL099390004
J 0
(-6325 5525);
DISPLAY 0.489362 (-6325 5525);
PAINT SKYBLUE (-6325 5525);
FORCEPROP 2 LAST CDS_LIB pure_quanta
J 0
(-6025 4725);
DISPLAY INVISIBLE (-6025 4725);
FORCEPROP 1 LAST CDS_LMAN_SYM_OUTLINE -300,700,250,-650
J 0
(-6025 4725);
DISPLAY 0.468085 (-6025 4725);
PAINT GREEN (-6025 4725);
DISPLAY INVISIBLE (-6025 4725);
FORCEPROP 1 LAST NEEDS_NO_SIZE TRUE
J 0
(-6025 4725);
DISPLAY 0.723404 (-6025 4725);
PAINT GREEN (-6025 4725);
DISPLAY INVISIBLE (-6025 4725);
FORCEPROP 1 LAST PATH I44
J 0
(-6025 4725);
DISPLAY 0.723404 (-6025 4725);
PAINT GREEN (-6025 4725);
DISPLAY INVISIBLE (-6025 4725);
FORCEADD OFFPAGE..1
(-8050 1850);
FORCEPROP 2 LAST $XR5 192 
J 0
(-8902 1850);
DISPLAY 0.638298 (-8902 1850);
PAINT MONO (-8902 1850);
FORCEPROP 2 LAST $XR4 191 
J 0
(-8782 1850);
DISPLAY 0.638298 (-8782 1850);
PAINT MONO (-8782 1850);
FORCEPROP 2 LAST $XR3 189 
J 0
(-8662 1850);
DISPLAY 0.638298 (-8662 1850);
PAINT MONO (-8662 1850);
FORCEPROP 2 LAST $XR2 188 
J 0
(-8542 1850);
DISPLAY 0.638298 (-8542 1850);
PAINT MONO (-8542 1850);
FORCEPROP 2 LAST $XR1 187 
J 0
(-8422 1850);
DISPLAY 0.638298 (-8422 1850);
PAINT MONO (-8422 1850);
FORCEPROP 2 LAST $XR0 186 
J 0
(-8302 1850);
DISPLAY 0.638298 (-8302 1850);
PAINT MONO (-8302 1850);
FORCEPROP 2 LAST PATH I45
J 0
(-8000 1925);
DISPLAY 1.021277 (-8000 1925);
DISPLAY INVISIBLE (-8000 1925);
FORCEPROP 1 LAST COMMENT_BODY TRUE
J 0
(-7925 1750);
DISPLAY 0.872340 (-7925 1750);
PAINT GREEN (-7925 1750);
DISPLAY INVISIBLE (-7925 1750);
FORCEPROP 1 LAST OFFPAGE TRUE
J 0
(-7725 1725);
DISPLAY 0.872340 (-7725 1725);
PAINT GREEN (-7725 1725);
DISPLAY INVISIBLE (-7725 1725);
FORCEPROP 2 LAST CDS_LIB standard
J 0
(-8050 1850);
DISPLAY INVISIBLE (-8050 1850);
FORCEADD UNIVERSAL_GND..1
(-5425 1250);
FORCEPROP 3 LASTPIN (-5425 1300) SIG_NAME GND\g
J 0
(-5415 1310);
DISPLAY 0.659574 (-5415 1310);
PAINT MONO (-5415 1310);
DISPLAY INVISIBLE (-5415 1310);
FORCEPROP 2 LAST CDS_LIB pure_quanta_power
J 0
(-5425 1250);
DISPLAY INVISIBLE (-5425 1250);
FORCEPROP 1 LAST PATH I46
J 0
(-5350 1250);
DISPLAY 0.872340 (-5350 1250);
PAINT AQUA (-5350 1250);
DISPLAY INVISIBLE (-5350 1250);
FORCEPROP 1 LAST HDL_POWER GND
J 1
(-5400 1175);
DISPLAY 0.872340 (-5400 1175);
PAINT GREEN (-5400 1175);
DISPLAY INVISIBLE (-5400 1175);
FORCEADD OFFPAGE..1
(-7100 1350);
FORCEPROP 2 LAST $XR0 186 
J 0
(-7382 1350);
DISPLAY 0.638298 (-7382 1350);
PAINT MONO (-7382 1350);
FORCEPROP 2 LAST PATH I47
J 0
(-7050 1425);
DISPLAY 1.021277 (-7050 1425);
DISPLAY INVISIBLE (-7050 1425);
FORCEPROP 1 LAST COMMENT_BODY TRUE
J 0
(-6975 1250);
DISPLAY 0.872340 (-6975 1250);
PAINT GREEN (-6975 1250);
DISPLAY INVISIBLE (-6975 1250);
FORCEPROP 1 LAST OFFPAGE TRUE
J 0
(-6775 1225);
DISPLAY 0.872340 (-6775 1225);
PAINT GREEN (-6775 1225);
DISPLAY INVISIBLE (-6775 1225);
FORCEPROP 2 LAST CDS_LIB standard
J 2
(-7100 1350);
DISPLAY INVISIBLE (-7100 1350);
FORCEADD Q_CAP..1
(-7825 1675);
FORCEPROP 1 LAST LOCATION PC318_8
J 0
(-7775 1775);
DISPLAY 0.489362 (-7775 1775);
PAINT SKYBLUE (-7775 1775);
FORCEPROP 0 LAST $SEC 1
J 0
(-7775 1800);
DISPLAY 0.680851 (-7775 1800);
PAINT MONO (-7775 1800);
DISPLAY INVISIBLE (-7775 1800);
FORCEPROP 0 LAST CDS_SEC 1
J 0
(-7775 1800);
DISPLAY 1.021277 (-7775 1800);
DISPLAY INVISIBLE (-7775 1800);
FORCEPROP 1 LASTPIN (-7825 1775) $PN 1
J 0
(-7815 1755);
DISPLAY 0.489362 (-7815 1755);
PAINT MONO (-7815 1755);
FORCEPROP 1 LASTPIN (-7825 1575) $PN 2
J 0
(-7815 1555);
DISPLAY 0.489362 (-7815 1555);
PAINT MONO (-7815 1555);
FORCEPROP 1 LAST MATERIAL X7R
J 0
(-7775 1575);
DISPLAY 0.489362 (-7775 1575);
PAINT SKYBLUE (-7775 1575);
FORCEPROP 1 LAST TOLERANCE 10%
J 0
(-7775 1625);
DISPLAY 0.489362 (-7775 1625);
PAINT SKYBLUE (-7775 1625);
FORCEPROP 1 LAST VALUE 0.1UF
J 0
(-7775 1725);
DISPLAY 0.489362 (-7775 1725);
PAINT SKYBLUE (-7775 1725);
FORCEPROP 1 LAST PART_NUMBER CH4104K1B00
J 0
(-7775 1525);
DISPLAY 0.489362 (-7775 1525);
PAINT SKYBLUE (-7775 1525);
FORCEPROP 1 LAST VOLTAGE 25V
J 0
(-7775 1675);
DISPLAY 0.489362 (-7775 1675);
PAINT SKYBLUE (-7775 1675);
FORCEPROP 1 LAST PACK_TYPE 0402
J 0
(-7775 1475);
DISPLAY 0.489362 (-7775 1475);
PAINT SKYBLUE (-7775 1475);
FORCEPROP 2 LAST CDS_LIB pure_quanta
J 0
(-7825 1675);
DISPLAY INVISIBLE (-7825 1675);
FORCEPROP 1 LAST PATH I48
J 0
(-7775 1825);
DISPLAY 0.978723 (-7775 1825);
PAINT WHITE (-7775 1825);
DISPLAY INVISIBLE (-7775 1825);
FORCEADD UNIVERSAL_GND..1
(-7825 1400);
FORCEPROP 3 LASTPIN (-7825 1450) SIG_NAME GND\g
J 0
(-7815 1460);
DISPLAY 0.659574 (-7815 1460);
PAINT MONO (-7815 1460);
DISPLAY INVISIBLE (-7815 1460);
FORCEPROP 2 LAST CDS_LIB pure_quanta_power
J 0
(-7825 1400);
DISPLAY INVISIBLE (-7825 1400);
FORCEPROP 1 LAST PATH I49
J 0
(-7750 1400);
DISPLAY 0.872340 (-7750 1400);
PAINT AQUA (-7750 1400);
DISPLAY INVISIBLE (-7750 1400);
FORCEPROP 1 LAST HDL_POWER GND
J 1
(-7800 1325);
DISPLAY 0.872340 (-7800 1325);
PAINT GREEN (-7800 1325);
DISPLAY INVISIBLE (-7800 1325);
FORCEADD UNIVERSAL_GND..1
(-7850 4175);
FORCEPROP 3 LASTPIN (-7850 4225) SIG_NAME GND\g
J 0
(-7840 4235);
DISPLAY 0.659574 (-7840 4235);
PAINT MONO (-7840 4235);
DISPLAY INVISIBLE (-7840 4235);
FORCEPROP 2 LAST CDS_LIB pure_quanta_power
J 0
(-7850 4175);
DISPLAY INVISIBLE (-7850 4175);
FORCEPROP 1 LAST PATH I5
J 0
(-7775 4175);
DISPLAY 0.872340 (-7775 4175);
PAINT AQUA (-7775 4175);
DISPLAY INVISIBLE (-7775 4175);
FORCEPROP 1 LAST HDL_POWER GND
J 1
(-7825 4100);
DISPLAY 0.872340 (-7825 4100);
PAINT GREEN (-7825 4100);
DISPLAY INVISIBLE (-7825 4100);
FORCEADD UNIVERSAL_GND..1
(-7500 1475);
FORCEPROP 3 LASTPIN (-7500 1525) SIG_NAME GND\g
J 0
(-7490 1535);
DISPLAY 0.659574 (-7490 1535);
PAINT MONO (-7490 1535);
DISPLAY INVISIBLE (-7490 1535);
FORCEPROP 2 LAST CDS_LIB pure_quanta_power
J 0
(-7500 1475);
DISPLAY INVISIBLE (-7500 1475);
FORCEPROP 1 LAST PATH I50
J 0
(-7425 1475);
DISPLAY 0.872340 (-7425 1475);
PAINT AQUA (-7425 1475);
DISPLAY INVISIBLE (-7425 1475);
FORCEPROP 1 LAST HDL_POWER GND
J 1
(-7475 1400);
DISPLAY 0.872340 (-7475 1400);
PAINT GREEN (-7475 1400);
DISPLAY INVISIBLE (-7475 1400);
FORCEADD OFFPAGE..2
R 2
(-7125 1450);
FORCEPROP 2 LAST $XR2 186 
J 0
(-7500 1414);
DISPLAY 0.638298 (-7500 1414);
PAINT MONO (-7500 1414);
FORCEPROP 2 LAST $XR1 192 
J 0
(-7380 1414);
DISPLAY 0.638298 (-7380 1414);
PAINT MONO (-7380 1414);
FORCEPROP 2 LAST $XR0 191 
J 0
(-7380 1450);
DISPLAY 0.638298 (-7380 1450);
PAINT MONO (-7380 1450);
FORCEPROP 2 LAST PATH I51
J 0
(-7075 1525);
DISPLAY 1.021277 (-7075 1525);
DISPLAY INVISIBLE (-7075 1525);
FORCEPROP 1 LAST COMMENT_BODY TRUE
J 2
(-7080 1355);
DISPLAY 0.872340 (-7080 1355);
PAINT GREEN (-7080 1355);
DISPLAY INVISIBLE (-7080 1355);
FORCEPROP 1 LAST OFFPAGE TRUE
J 2
(-7450 1325);
DISPLAY 0.872340 (-7450 1325);
PAINT GREEN (-7450 1325);
DISPLAY INVISIBLE (-7450 1325);
FORCEPROP 2 LAST CDS_LIB standard
J 0
(-7125 1450);
DISPLAY INVISIBLE (-7125 1450);
FORCEADD Q_RES..1
(-7150 1650);
FORCEPROP 1 LAST LOCATION PR208
J 0
(-7150 1700);
DISPLAY 0.489362 (-7150 1700);
PAINT SKYBLUE (-7150 1700);
FORCEPROP 0 LAST $SEC 1
J 0
(-7150 1725);
DISPLAY 0.680851 (-7150 1725);
PAINT MONO (-7150 1725);
DISPLAY INVISIBLE (-7150 1725);
FORCEPROP 0 LAST CDS_SEC 1
J 0
(-7150 1725);
DISPLAY 1.021277 (-7150 1725);
DISPLAY INVISIBLE (-7150 1725);
FORCEPROP 1 LASTPIN (-7250 1650) $PN 1
J 0
(-7238 1662);
DISPLAY 0.489362 (-7238 1662);
PAINT MONO (-7238 1662);
FORCEPROP 1 LASTPIN (-7050 1650) $PN 2
J 0
(-7088 1662);
DISPLAY 0.489362 (-7088 1662);
PAINT MONO (-7088 1662);
FORCEPROP 1 LAST WATTAGE 1/16W
J 0
(-7050 1550);
DISPLAY 0.489362 (-7050 1550);
PAINT SKYBLUE (-7050 1550);
FORCEPROP 1 LAST MATERIAL EMPTY
J 0
(-7450 1550);
DISPLAY 0.489362 (-7450 1550);
PAINT RED (-7450 1550);
FORCEPROP 1 LAST TOLERANCE 1%
J 0
(-7025 1675);
DISPLAY 0.489362 (-7025 1675);
PAINT SKYBLUE (-7025 1675);
FORCEPROP 1 LAST VALUE 8.87K
J 2
(-7275 1675);
DISPLAY 0.489362 (-7275 1675);
PAINT SKYBLUE (-7275 1675);
FORCEPROP 1 LAST PART_NUMBER CS28872FB01
J 0
(-7450 1600);
DISPLAY 0.489362 (-7450 1600);
PAINT SKYBLUE (-7450 1600);
FORCEPROP 1 LAST PACK_TYPE 0402LF
J 0
(-7050 1600);
DISPLAY 0.489362 (-7050 1600);
PAINT SKYBLUE (-7050 1600);
FORCEPROP 2 LAST CDS_LIB pure_quanta
J 0
(-7150 1650);
DISPLAY INVISIBLE (-7150 1650);
FORCEPROP 1 LAST PATH I52
J 0
(-7200 1800);
DISPLAY 0.978723 (-7200 1800);
PAINT WHITE (-7200 1800);
DISPLAY INVISIBLE (-7200 1800);
FORCEADD OFFPAGE..2
R 2
(-7150 1950);
FORCEPROP 2 LAST $XR0 186 
J 0
(-7435 1950);
DISPLAY 0.638298 (-7435 1950);
PAINT MONO (-7435 1950);
FORCEPROP 2 LAST PATH I55
J 0
(-7100 2025);
DISPLAY 1.021277 (-7100 2025);
DISPLAY INVISIBLE (-7100 2025);
FORCEPROP 1 LAST COMMENT_BODY TRUE
J 2
(-7105 1855);
DISPLAY 0.872340 (-7105 1855);
PAINT GREEN (-7105 1855);
DISPLAY INVISIBLE (-7105 1855);
FORCEPROP 1 LAST OFFPAGE TRUE
J 2
(-7475 1825);
DISPLAY 0.872340 (-7475 1825);
PAINT GREEN (-7475 1825);
DISPLAY INVISIBLE (-7475 1825);
FORCEPROP 2 LAST CDS_LIB standard
J 2
(-7150 1950);
DISPLAY INVISIBLE (-7150 1950);
FORCEADD UNIVERSAL_GND..1
(-7525 4250);
FORCEPROP 3 LASTPIN (-7525 4300) SIG_NAME GND\g
J 0
(-7515 4310);
DISPLAY 0.659574 (-7515 4310);
PAINT MONO (-7515 4310);
DISPLAY INVISIBLE (-7515 4310);
FORCEPROP 2 LAST CDS_LIB pure_quanta_power
J 0
(-7525 4250);
DISPLAY INVISIBLE (-7525 4250);
FORCEPROP 1 LAST PATH I6
J 0
(-7450 4250);
DISPLAY 0.872340 (-7450 4250);
PAINT AQUA (-7450 4250);
DISPLAY INVISIBLE (-7450 4250);
FORCEPROP 1 LAST HDL_POWER GND
J 1
(-7500 4175);
DISPLAY 0.872340 (-7500 4175);
PAINT GREEN (-7500 4175);
DISPLAY INVISIBLE (-7500 4175);
FORCEADD Q_RES..1
(-4675 2300);
FORCEPROP 1 LAST LOCATION PR210
J 0
(-4700 2350);
DISPLAY 0.489362 (-4700 2350);
PAINT SKYBLUE (-4700 2350);
FORCEPROP 0 LAST $SEC 1
J 0
(-4650 2375);
DISPLAY 0.680851 (-4650 2375);
PAINT MONO (-4650 2375);
DISPLAY INVISIBLE (-4650 2375);
FORCEPROP 0 LAST CDS_SEC 1
J 0
(-4650 2375);
DISPLAY 1.021277 (-4650 2375);
DISPLAY INVISIBLE (-4650 2375);
FORCEPROP 1 LASTPIN (-4775 2300) $PN 1
J 0
(-4763 2312);
DISPLAY 0.489362 (-4763 2312);
PAINT MONO (-4763 2312);
FORCEPROP 1 LASTPIN (-4575 2300) $PN 2
J 0
(-4613 2312);
DISPLAY 0.489362 (-4613 2312);
PAINT MONO (-4613 2312);
FORCEPROP 1 LAST PACK_TYPE 0402LF
J 0
(-4575 2200);
DISPLAY 0.489362 (-4575 2200);
PAINT SKYBLUE (-4575 2200);
FORCEPROP 1 LAST TOLERANCE 1%
J 0
(-4550 2325);
DISPLAY 0.489362 (-4550 2325);
PAINT SKYBLUE (-4550 2325);
FORCEPROP 1 LAST MATERIAL CHIP
J 0
(-4925 2200);
DISPLAY 0.489362 (-4925 2200);
PAINT SKYBLUE (-4925 2200);
FORCEPROP 1 LAST WATTAGE 1/16W
J 0
(-4575 2250);
DISPLAY 0.489362 (-4575 2250);
PAINT SKYBLUE (-4575 2250);
FORCEPROP 1 LAST VALUE 4.7
J 2
(-4800 2325);
DISPLAY 0.489362 (-4800 2325);
PAINT SKYBLUE (-4800 2325);
FORCEPROP 1 LAST PART_NUMBER CS-4702FB19
J 0
(-4925 2250);
DISPLAY 0.489362 (-4925 2250);
PAINT SKYBLUE (-4925 2250);
FORCEPROP 1 LAST PATH I63
J 0
(-4725 2450);
DISPLAY 0.978723 (-4725 2450);
PAINT WHITE (-4725 2450);
DISPLAY INVISIBLE (-4725 2450);
FORCEPROP 2 LAST CDS_LIB pure_quanta
J 0
(-4675 2300);
DISPLAY INVISIBLE (-4675 2300);
FORCEADD Q_RES..1
(-4250 775);
FORCEPROP 1 LAST LOCATION PR212
J 0
(-4275 825);
DISPLAY 0.489362 (-4275 825);
PAINT SKYBLUE (-4275 825);
FORCEPROP 0 LAST $SEC 1
J 0
(-4250 850);
DISPLAY 0.680851 (-4250 850);
PAINT MONO (-4250 850);
DISPLAY INVISIBLE (-4250 850);
FORCEPROP 0 LAST CDS_SEC 1
J 0
(-4250 850);
DISPLAY 1.021277 (-4250 850);
DISPLAY INVISIBLE (-4250 850);
FORCEPROP 1 LASTPIN (-4350 775) $PN 1
J 0
(-4338 787);
DISPLAY 0.489362 (-4338 787);
PAINT MONO (-4338 787);
FORCEPROP 1 LASTPIN (-4150 775) $PN 2
J 0
(-4188 787);
DISPLAY 0.489362 (-4188 787);
PAINT MONO (-4188 787);
FORCEPROP 1 LAST VALUE 0
J 2
(-4375 800);
DISPLAY 0.489362 (-4375 800);
PAINT SKYBLUE (-4375 800);
FORCEPROP 1 LAST WATTAGE 1/16W
J 0
(-4150 725);
DISPLAY 0.489362 (-4150 725);
PAINT SKYBLUE (-4150 725);
FORCEPROP 1 LAST MATERIAL CHIP
J 0
(-4500 675);
DISPLAY 0.489362 (-4500 675);
PAINT SKYBLUE (-4500 675);
FORCEPROP 1 LAST TOLERANCE 5%
J 0
(-4125 800);
DISPLAY 0.489362 (-4125 800);
PAINT SKYBLUE (-4125 800);
FORCEPROP 1 LAST PART_NUMBER CS00002JB38
J 0
(-4500 725);
DISPLAY 0.489362 (-4500 725);
PAINT SKYBLUE (-4500 725);
FORCEPROP 1 LAST PACK_TYPE 0402LF
J 0
(-4150 675);
DISPLAY 0.489362 (-4150 675);
PAINT SKYBLUE (-4150 675);
FORCEPROP 2 LAST CDS_LIB pure_quanta
J 0
(-4250 775);
DISPLAY INVISIBLE (-4250 775);
FORCEPROP 1 LAST PATH I65
J 0
(-4300 925);
DISPLAY 0.978723 (-4300 925);
PAINT WHITE (-4300 925);
DISPLAY INVISIBLE (-4300 925);
FORCEADD Q_CAP..1
(-3800 2175);
FORCEPROP 1 LAST LOCATION PC334
J 0
(-3750 2300);
DISPLAY 0.489362 (-3750 2300);
PAINT SKYBLUE (-3750 2300);
FORCEPROP 0 LAST $SEC 1
J 0
(-3750 2325);
DISPLAY 0.680851 (-3750 2325);
PAINT MONO (-3750 2325);
DISPLAY INVISIBLE (-3750 2325);
FORCEPROP 0 LAST CDS_SEC 1
J 0
(-3750 2325);
DISPLAY 1.021277 (-3750 2325);
DISPLAY INVISIBLE (-3750 2325);
FORCEPROP 1 LASTPIN (-3800 2275) $PN 1
J 0
(-3790 2255);
DISPLAY 0.489362 (-3790 2255);
PAINT MONO (-3790 2255);
FORCEPROP 1 LASTPIN (-3800 2075) $PN 2
J 0
(-3790 2055);
DISPLAY 0.489362 (-3790 2055);
PAINT MONO (-3790 2055);
FORCEPROP 1 LAST MATERIAL X7R
J 0
(-3750 2100);
DISPLAY 0.489362 (-3750 2100);
PAINT SKYBLUE (-3750 2100);
FORCEPROP 1 LAST TOLERANCE 10%
J 0
(-3750 2150);
DISPLAY 0.489362 (-3750 2150);
PAINT SKYBLUE (-3750 2150);
FORCEPROP 1 LAST VALUE 0.22UF
J 0
(-3750 2250);
DISPLAY 0.489362 (-3750 2250);
PAINT SKYBLUE (-3750 2250);
FORCEPROP 1 LAST PART_NUMBER CH4223K1B00
J 0
(-3750 2050);
DISPLAY 0.489362 (-3750 2050);
PAINT SKYBLUE (-3750 2050);
FORCEPROP 1 LAST VOLTAGE 16V
J 0
(-3750 2200);
DISPLAY 0.489362 (-3750 2200);
PAINT SKYBLUE (-3750 2200);
FORCEPROP 1 LAST PACK_TYPE 0402
J 0
(-3750 2000);
DISPLAY 0.489362 (-3750 2000);
PAINT SKYBLUE (-3750 2000);
FORCEPROP 2 LAST CDS_LIB pure_quanta
J 0
(-3800 2175);
DISPLAY INVISIBLE (-3800 2175);
FORCEPROP 1 LAST PATH I66
J 0
(-3750 2325);
DISPLAY 0.978723 (-3750 2325);
PAINT WHITE (-3750 2325);
DISPLAY INVISIBLE (-3750 2325);
FORCEADD Q_CAP..1
(-4975 2850);
FORCEPROP 1 LAST LOCATION PC326_2
J 0
(-4925 2950);
DISPLAY 0.489362 (-4925 2950);
PAINT SKYBLUE (-4925 2950);
FORCEPROP 0 LAST $SEC 1
J 0
(-4925 2975);
DISPLAY 0.680851 (-4925 2975);
PAINT MONO (-4925 2975);
DISPLAY INVISIBLE (-4925 2975);
FORCEPROP 0 LAST CDS_SEC 1
J 0
(-4925 2975);
DISPLAY 1.021277 (-4925 2975);
DISPLAY INVISIBLE (-4925 2975);
FORCEPROP 1 LASTPIN (-4975 2950) $PN 1
J 0
(-4965 2930);
DISPLAY 0.489362 (-4965 2930);
PAINT MONO (-4965 2930);
FORCEPROP 1 LASTPIN (-4975 2750) $PN 2
J 0
(-4965 2730);
DISPLAY 0.489362 (-4965 2730);
PAINT MONO (-4965 2730);
FORCEPROP 1 LAST MATERIAL X6S
J 0
(-4925 2750);
DISPLAY 0.489362 (-4925 2750);
PAINT SKYBLUE (-4925 2750);
FORCEPROP 1 LAST TOLERANCE 10%
J 0
(-4925 2800);
DISPLAY 0.489362 (-4925 2800);
PAINT SKYBLUE (-4925 2800);
FORCEPROP 1 LAST VALUE 1UF
J 0
(-4925 2900);
DISPLAY 0.489362 (-4925 2900);
PAINT SKYBLUE (-4925 2900);
FORCEPROP 1 LAST PART_NUMBER CH5104KEB02
J 0
(-4925 2700);
DISPLAY 0.489362 (-4925 2700);
PAINT SKYBLUE (-4925 2700);
FORCEPROP 1 LAST VOLTAGE 25V
J 0
(-4925 2850);
DISPLAY 0.489362 (-4925 2850);
PAINT SKYBLUE (-4925 2850);
FORCEPROP 1 LAST PACK_TYPE C0402
J 0
(-4925 2650);
DISPLAY 0.489362 (-4925 2650);
PAINT SKYBLUE (-4925 2650);
FORCEPROP 2 LAST CDS_LIB pure_quanta
J 0
(-4975 2850);
DISPLAY INVISIBLE (-4975 2850);
FORCEPROP 1 LAST PATH I67
J 0
(-4925 3000);
DISPLAY 0.978723 (-4925 3000);
PAINT WHITE (-4925 3000);
DISPLAY INVISIBLE (-4925 3000);
FORCEADD Q_CAP..1
(-4650 2850);
FORCEPROP 1 LAST LOCATION PC328_2
J 0
(-4600 2950);
DISPLAY 0.489362 (-4600 2950);
PAINT SKYBLUE (-4600 2950);
FORCEPROP 0 LAST $SEC 1
J 0
(-4600 2975);
DISPLAY 0.680851 (-4600 2975);
PAINT MONO (-4600 2975);
DISPLAY INVISIBLE (-4600 2975);
FORCEPROP 0 LAST CDS_SEC 1
J 0
(-4600 2975);
DISPLAY 1.021277 (-4600 2975);
DISPLAY INVISIBLE (-4600 2975);
FORCEPROP 1 LASTPIN (-4650 2950) $PN 1
J 0
(-4640 2930);
DISPLAY 0.489362 (-4640 2930);
PAINT MONO (-4640 2930);
FORCEPROP 1 LASTPIN (-4650 2750) $PN 2
J 0
(-4640 2730);
DISPLAY 0.489362 (-4640 2730);
PAINT MONO (-4640 2730);
FORCEPROP 1 LAST MATERIAL X6S
J 0
(-4600 2750);
DISPLAY 0.489362 (-4600 2750);
PAINT SKYBLUE (-4600 2750);
FORCEPROP 1 LAST TOLERANCE 10%
J 0
(-4600 2800);
DISPLAY 0.489362 (-4600 2800);
PAINT SKYBLUE (-4600 2800);
FORCEPROP 1 LAST VALUE 10UF
J 0
(-4600 2900);
DISPLAY 0.489362 (-4600 2900);
PAINT SKYBLUE (-4600 2900);
FORCEPROP 1 LAST PART_NUMBER CH6104KEA00
J 0
(-4600 2700);
DISPLAY 0.489362 (-4600 2700);
PAINT SKYBLUE (-4600 2700);
FORCEPROP 1 LAST VOLTAGE 25V
J 0
(-4600 2850);
DISPLAY 0.489362 (-4600 2850);
PAINT SKYBLUE (-4600 2850);
FORCEPROP 1 LAST PACK_TYPE C0805
J 0
(-4600 2650);
DISPLAY 0.489362 (-4600 2650);
PAINT SKYBLUE (-4600 2650);
FORCEPROP 2 LAST CDS_LIB pure_quanta
J 0
(-4650 2850);
DISPLAY INVISIBLE (-4650 2850);
FORCEPROP 1 LAST PATH I68
J 0
(-4600 3000);
DISPLAY 0.978723 (-4600 3000);
PAINT WHITE (-4600 3000);
DISPLAY INVISIBLE (-4600 3000);
FORCEADD Q_CAP..1
(-4325 2850);
FORCEPROP 1 LAST LOCATION PC330_2
J 0
(-4275 2950);
DISPLAY 0.489362 (-4275 2950);
PAINT SKYBLUE (-4275 2950);
FORCEPROP 0 LAST $SEC 1
J 0
(-4275 2975);
DISPLAY 0.680851 (-4275 2975);
PAINT MONO (-4275 2975);
DISPLAY INVISIBLE (-4275 2975);
FORCEPROP 0 LAST CDS_SEC 1
J 0
(-4275 2975);
DISPLAY 1.021277 (-4275 2975);
DISPLAY INVISIBLE (-4275 2975);
FORCEPROP 1 LASTPIN (-4325 2950) $PN 1
J 0
(-4315 2930);
DISPLAY 0.489362 (-4315 2930);
PAINT MONO (-4315 2930);
FORCEPROP 1 LASTPIN (-4325 2750) $PN 2
J 0
(-4315 2730);
DISPLAY 0.489362 (-4315 2730);
PAINT MONO (-4315 2730);
FORCEPROP 1 LAST MATERIAL X6S
J 0
(-4275 2750);
DISPLAY 0.489362 (-4275 2750);
PAINT SKYBLUE (-4275 2750);
FORCEPROP 1 LAST TOLERANCE 10%
J 0
(-4275 2800);
DISPLAY 0.489362 (-4275 2800);
PAINT SKYBLUE (-4275 2800);
FORCEPROP 1 LAST VALUE 10UF
J 0
(-4275 2900);
DISPLAY 0.489362 (-4275 2900);
PAINT SKYBLUE (-4275 2900);
FORCEPROP 1 LAST PART_NUMBER CH6104KEA00
J 0
(-4275 2700);
DISPLAY 0.489362 (-4275 2700);
PAINT SKYBLUE (-4275 2700);
FORCEPROP 1 LAST VOLTAGE 25V
J 0
(-4275 2850);
DISPLAY 0.489362 (-4275 2850);
PAINT SKYBLUE (-4275 2850);
FORCEPROP 1 LAST PACK_TYPE C0805
J 0
(-4275 2650);
DISPLAY 0.489362 (-4275 2650);
PAINT SKYBLUE (-4275 2650);
FORCEPROP 2 LAST CDS_LIB pure_quanta
J 0
(-4325 2850);
DISPLAY INVISIBLE (-4325 2850);
FORCEPROP 1 LAST PATH I69
J 0
(-4275 3000);
DISPLAY 0.978723 (-4275 3000);
PAINT WHITE (-4275 3000);
DISPLAY INVISIBLE (-4275 3000);
FORCEADD OFFPAGE..2
R 2
(-7150 4225);
FORCEPROP 2 LAST $XR2 186 
J 0
(-7555 4189);
DISPLAY 0.638298 (-7555 4189);
PAINT MONO (-7555 4189);
FORCEPROP 2 LAST $XR1 192 
J 0
(-7435 4189);
DISPLAY 0.638298 (-7435 4189);
PAINT MONO (-7435 4189);
FORCEPROP 2 LAST $XR0 191 
J 0
(-7435 4225);
DISPLAY 0.638298 (-7435 4225);
PAINT MONO (-7435 4225);
FORCEPROP 2 LAST CDS_LIB standard
J 0
(-7150 4225);
DISPLAY INVISIBLE (-7150 4225);
FORCEPROP 1 LAST OFFPAGE TRUE
J 2
(-7475 4100);
DISPLAY 0.872340 (-7475 4100);
PAINT GREEN (-7475 4100);
DISPLAY INVISIBLE (-7475 4100);
FORCEPROP 1 LAST COMMENT_BODY TRUE
J 2
(-7105 4130);
DISPLAY 0.872340 (-7105 4130);
PAINT GREEN (-7105 4130);
DISPLAY INVISIBLE (-7105 4130);
FORCEPROP 2 LAST PATH I7
J 0
(-7100 4300);
DISPLAY 1.021277 (-7100 4300);
DISPLAY INVISIBLE (-7100 4300);
FORCEADD Q_CAP..1
(-4025 2850);
FORCEPROP 1 LAST LOCATION PC332_2
J 0
(-3975 2950);
DISPLAY 0.489362 (-3975 2950);
PAINT SKYBLUE (-3975 2950);
FORCEPROP 0 LAST $SEC 1
J 0
(-3975 2975);
DISPLAY 0.680851 (-3975 2975);
PAINT MONO (-3975 2975);
DISPLAY INVISIBLE (-3975 2975);
FORCEPROP 0 LAST CDS_SEC 1
J 0
(-3975 2975);
DISPLAY 1.021277 (-3975 2975);
DISPLAY INVISIBLE (-3975 2975);
FORCEPROP 1 LASTPIN (-4025 2950) $PN 1
J 0
(-4015 2930);
DISPLAY 0.489362 (-4015 2930);
PAINT MONO (-4015 2930);
FORCEPROP 1 LASTPIN (-4025 2750) $PN 2
J 0
(-4015 2730);
DISPLAY 0.489362 (-4015 2730);
PAINT MONO (-4015 2730);
FORCEPROP 1 LAST MATERIAL X6S
J 0
(-3975 2750);
DISPLAY 0.489362 (-3975 2750);
PAINT SKYBLUE (-3975 2750);
FORCEPROP 1 LAST TOLERANCE 10%
J 0
(-3975 2800);
DISPLAY 0.489362 (-3975 2800);
PAINT SKYBLUE (-3975 2800);
FORCEPROP 1 LAST VALUE 10UF
J 0
(-3975 2900);
DISPLAY 0.489362 (-3975 2900);
PAINT SKYBLUE (-3975 2900);
FORCEPROP 1 LAST PART_NUMBER CH6104KEA00
J 0
(-3975 2700);
DISPLAY 0.489362 (-3975 2700);
PAINT SKYBLUE (-3975 2700);
FORCEPROP 1 LAST VOLTAGE 25V
J 0
(-3975 2850);
DISPLAY 0.489362 (-3975 2850);
PAINT SKYBLUE (-3975 2850);
FORCEPROP 1 LAST PACK_TYPE C0805
J 0
(-3975 2650);
DISPLAY 0.489362 (-3975 2650);
PAINT SKYBLUE (-3975 2650);
FORCEPROP 2 LAST CDS_LIB pure_quanta
J 0
(-4025 2850);
DISPLAY INVISIBLE (-4025 2850);
FORCEPROP 1 LAST PATH I70
J 0
(-3975 3000);
DISPLAY 0.978723 (-3975 3000);
PAINT WHITE (-3975 3000);
DISPLAY INVISIBLE (-3975 3000);
FORCEADD UNIVERSAL_GND..1
(-3700 2525);
FORCEPROP 3 LASTPIN (-3700 2575) SIG_NAME GND\g
J 0
(-3690 2585);
DISPLAY 0.659574 (-3690 2585);
PAINT MONO (-3690 2585);
DISPLAY INVISIBLE (-3690 2585);
FORCEPROP 2 LAST CDS_LIB pure_quanta_power
J 0
(-3700 2525);
DISPLAY INVISIBLE (-3700 2525);
FORCEPROP 1 LAST PATH I71
J 0
(-3625 2525);
DISPLAY 0.872340 (-3625 2525);
PAINT AQUA (-3625 2525);
DISPLAY INVISIBLE (-3625 2525);
FORCEPROP 1 LAST HDL_POWER GND
J 1
(-3675 2450);
DISPLAY 0.872340 (-3675 2450);
PAINT GREEN (-3675 2450);
DISPLAY INVISIBLE (-3675 2450);
FORCEADD VCC_CORE..1
(-3700 3150);
FORCEPROP 3 LASTPIN (-3700 3100) SIG_NAME SW_P12V_STBY_PVDDCR_SOC_P1_FLT\g
J 0
(-3690 3110);
DISPLAY 0.659574 (-3690 3110);
PAINT MONO (-3690 3110);
DISPLAY INVISIBLE (-3690 3110);
FORCEPROP 1 LAST HDL_POWER SW_P12V_STBY_PVDDCR_SOC_P1_FLT
J 1
(-3700 3200);
DISPLAY 0.489362 (-3700 3200);
PAINT GREEN (-3700 3200);
FORCEPROP 2 LAST CDS_LIB pure_quanta_power
J 0
(-3700 3150);
DISPLAY INVISIBLE (-3700 3150);
FORCEPROP 1 LAST PATH I73
J 0
(-3650 3175);
DISPLAY 0.872340 (-3650 3175);
PAINT AQUA (-3650 3175);
DISPLAY INVISIBLE (-3650 3175);
FORCEADD Q_CAP..1
(-1675 1775);
FORCEPROP 1 LAST LOCATION PC339_2
J 0
(-1625 1875);
DISPLAY 0.489362 (-1625 1875);
PAINT SKYBLUE (-1625 1875);
FORCEPROP 0 LAST $SEC 1
J 0
(-1625 1900);
DISPLAY 0.680851 (-1625 1900);
PAINT MONO (-1625 1900);
DISPLAY INVISIBLE (-1625 1900);
FORCEPROP 0 LAST CDS_SEC 1
J 0
(-1625 1900);
DISPLAY 1.021277 (-1625 1900);
DISPLAY INVISIBLE (-1625 1900);
FORCEPROP 1 LASTPIN (-1675 1875) $PN 1
J 0
(-1665 1855);
DISPLAY 0.489362 (-1665 1855);
PAINT MONO (-1665 1855);
FORCEPROP 1 LASTPIN (-1675 1675) $PN 2
J 0
(-1665 1655);
DISPLAY 0.489362 (-1665 1655);
PAINT MONO (-1665 1655);
FORCEPROP 1 LAST MATERIAL X6S
J 0
(-1625 1675);
DISPLAY 0.489362 (-1625 1675);
PAINT SKYBLUE (-1625 1675);
FORCEPROP 1 LAST TOLERANCE 20%
J 0
(-1625 1725);
DISPLAY 0.489362 (-1625 1725);
PAINT SKYBLUE (-1625 1725);
FORCEPROP 1 LAST VALUE 22UF
J 0
(-1625 1825);
DISPLAY 0.489362 (-1625 1825);
PAINT SKYBLUE (-1625 1825);
FORCEPROP 1 LAST PART_NUMBER TMP_QCH622KMEA01
J 0
(-1625 1625);
DISPLAY 0.489362 (-1625 1625);
PAINT SKYBLUE (-1625 1625);
FORCEPROP 1 LAST VOLTAGE 4V
J 0
(-1625 1775);
DISPLAY 0.489362 (-1625 1775);
PAINT SKYBLUE (-1625 1775);
FORCEPROP 1 LAST PACK_TYPE 0805
J 0
(-1625 1575);
DISPLAY 0.489362 (-1625 1575);
PAINT SKYBLUE (-1625 1575);
FORCEPROP 2 LAST CDS_LIB pure_quanta
J 0
(-1675 1775);
DISPLAY INVISIBLE (-1675 1775);
FORCEPROP 1 LAST PATH I79
J 0
(-1625 1925);
DISPLAY 0.978723 (-1625 1925);
PAINT WHITE (-1625 1925);
DISPLAY INVISIBLE (-1625 1925);
FORCEADD UNIVERSAL_GND..1
(-1250 1425);
FORCEPROP 3 LASTPIN (-1250 1475) SIG_NAME GND\g
J 0
(-1240 1485);
DISPLAY 0.659574 (-1240 1485);
PAINT MONO (-1240 1485);
DISPLAY INVISIBLE (-1240 1485);
FORCEPROP 2 LAST CDS_LIB pure_quanta_power
J 0
(-1250 1425);
DISPLAY INVISIBLE (-1250 1425);
FORCEPROP 1 LAST PATH I80
J 0
(-1175 1425);
DISPLAY 0.872340 (-1175 1425);
PAINT AQUA (-1175 1425);
DISPLAY INVISIBLE (-1175 1425);
FORCEPROP 1 LAST HDL_POWER GND
J 1
(-1225 1350);
DISPLAY 0.872340 (-1225 1350);
PAINT GREEN (-1225 1350);
DISPLAY INVISIBLE (-1225 1350);
FORCEADD Q_CAP..1
(-1250 1775);
FORCEPROP 1 LAST LOCATION PC342_2
J 0
(-1200 1875);
DISPLAY 0.489362 (-1200 1875);
PAINT SKYBLUE (-1200 1875);
FORCEPROP 0 LAST $SEC 1
J 0
(-1200 1900);
DISPLAY 0.680851 (-1200 1900);
PAINT MONO (-1200 1900);
DISPLAY INVISIBLE (-1200 1900);
FORCEPROP 0 LAST CDS_SEC 1
J 0
(-1200 1900);
DISPLAY 1.021277 (-1200 1900);
DISPLAY INVISIBLE (-1200 1900);
FORCEPROP 1 LASTPIN (-1250 1875) $PN 1
J 0
(-1240 1855);
DISPLAY 0.489362 (-1240 1855);
PAINT MONO (-1240 1855);
FORCEPROP 1 LASTPIN (-1250 1675) $PN 2
J 0
(-1240 1655);
DISPLAY 0.489362 (-1240 1655);
PAINT MONO (-1240 1655);
FORCEPROP 1 LAST MATERIAL X6S
J 0
(-1200 1675);
DISPLAY 0.489362 (-1200 1675);
PAINT SKYBLUE (-1200 1675);
FORCEPROP 1 LAST TOLERANCE 20%
J 0
(-1200 1725);
DISPLAY 0.489362 (-1200 1725);
PAINT SKYBLUE (-1200 1725);
FORCEPROP 1 LAST VALUE 22UF
J 0
(-1200 1825);
DISPLAY 0.489362 (-1200 1825);
PAINT SKYBLUE (-1200 1825);
FORCEPROP 1 LAST PART_NUMBER TMP_QCH622KMEA01
J 0
(-1200 1625);
DISPLAY 0.489362 (-1200 1625);
PAINT SKYBLUE (-1200 1625);
FORCEPROP 1 LAST VOLTAGE 4V
J 0
(-1200 1775);
DISPLAY 0.489362 (-1200 1775);
PAINT SKYBLUE (-1200 1775);
FORCEPROP 1 LAST PACK_TYPE 0805
J 0
(-1200 1575);
DISPLAY 0.489362 (-1200 1575);
PAINT SKYBLUE (-1200 1575);
FORCEPROP 2 LAST CDS_LIB pure_quanta
J 0
(-1250 1775);
DISPLAY INVISIBLE (-1250 1775);
FORCEPROP 1 LAST PATH I81
J 0
(-1200 1925);
DISPLAY 0.978723 (-1200 1925);
PAINT WHITE (-1200 1925);
DISPLAY INVISIBLE (-1200 1925);
FORCEADD VCC_CORE..1
(-1250 2100);
FORCEPROP 3 LASTPIN (-1250 2050) SIG_NAME PVDDCR_SOC_P1\g
J 0
(-1240 2060);
DISPLAY 0.659574 (-1240 2060);
PAINT MONO (-1240 2060);
DISPLAY INVISIBLE (-1240 2060);
FORCEPROP 1 LAST HDL_POWER PVDDCR_SOC_P1
J 1
(-1250 2150);
DISPLAY 0.489362 (-1250 2150);
PAINT GREEN (-1250 2150);
FORCEPROP 2 LAST CDS_LIB pure_quanta_power
J 0
(-1250 2100);
DISPLAY INVISIBLE (-1250 2100);
FORCEPROP 1 LAST PATH I82
J 0
(-1200 2125);
DISPLAY 0.872340 (-1200 2125);
PAINT AQUA (-1200 2125);
DISPLAY INVISIBLE (-1200 2125);
FORCEADD Q_INDUCTOR4P_14..1
(-2925 1825);
FORCEPROP 1 LAST LOCATION PL36
J 0
(-3150 2080);
DISPLAY 0.489362 (-3150 2080);
PAINT SKYBLUE (-3150 2080);
FORCEPROP 0 LAST $SEC 1
J 0
(-3150 2225);
DISPLAY 0.680851 (-3150 2225);
PAINT MONO (-3150 2225);
DISPLAY INVISIBLE (-3150 2225);
FORCEPROP 0 LAST CDS_SEC 1
J 0
(-3150 2225);
DISPLAY 1.021277 (-3150 2225);
DISPLAY INVISIBLE (-3150 2225);
FORCEPROP 0 LASTPIN (-3325 1950) $PN 1
J 2
(-3335 1960);
DISPLAY 0.489362 (-3335 1960);
PAINT MONO (-3335 1960);
FORCEPROP 0 LASTPIN (-3325 1700) $PN 2
J 2
(-3335 1710);
DISPLAY 0.489362 (-3335 1710);
PAINT MONO (-3335 1710);
FORCEPROP 0 LASTPIN (-2525 1700) $PN 3
J 0
(-2515 1710);
DISPLAY 0.489362 (-2515 1710);
PAINT MONO (-2515 1710);
FORCEPROP 0 LASTPIN (-2525 1950) $PN 4
J 0
(-2515 1960);
DISPLAY 0.489362 (-2515 1960);
PAINT MONO (-2515 1960);
FORCEPROP 2 LAST VALUE 150NH
J 0
(-3150 2125);
DISPLAY 0.489362 (-3150 2125);
PAINT SKYBLUE (-3150 2125);
FORCEPROP 2 LAST PART_TYPE SMLF
J 0
(-3150 2175);
DISPLAY 1.021277 (-3150 2175);
FORCEPROP 1 LAST MATERIAL IND
J 0
(-3150 2035);
DISPLAY 0.489362 (-3150 2035);
PAINT SKYBLUE (-3150 2035);
FORCEPROP 1 LAST PART_NUMBER CV+15^0TZ04
J 0
(-3150 1985);
DISPLAY 0.489362 (-3150 1985);
PAINT SKYBLUE (-3150 1985);
FORCEPROP 2 LAST CDS_LIB pure_quanta
J 0
(-2925 1825);
DISPLAY INVISIBLE (-2925 1825);
FORCEPROP 1 LAST NEEDS_NO_SIZE TRUE
J 0
(-2925 1825);
DISPLAY 0.468085 (-2925 1825);
PAINT GREEN (-2925 1825);
DISPLAY INVISIBLE (-2925 1825);
FORCEPROP 1 LAST PATH I83
J 0
(-2725 1980);
DISPLAY 0.723404 (-2725 1980);
PAINT GREEN (-2725 1980);
DISPLAY INVISIBLE (-2725 1980);
FORCEADD ISL99390FRZTR5935..1
(-6000 1950);
FORCEPROP 1 LAST LOCATION PU31
J 0
(-6300 2825);
DISPLAY 0.489362 (-6300 2825);
PAINT SKYBLUE (-6300 2825);
FORCEPROP 2 LAST $SEC 1
J 0
(-6300 2975);
DISPLAY 0.680851 (-6300 2975);
PAINT MONO (-6300 2975);
DISPLAY INVISIBLE (-6300 2975);
FORCEPROP 2 LAST CDS_SEC 1
J 0
(-6300 2975);
DISPLAY 1.021277 (-6300 2975);
DISPLAY INVISIBLE (-6300 2975);
FORCEPROP 2 LASTPIN (-5600 1500) $PN 2
J 0
(-5590 1510);
DISPLAY 0.489362 (-5590 1510);
PAINT MONO (-5590 1510);
FORCEPROP 2 LASTPIN (-5600 2300) $PN 33
J 0
(-5590 2310);
DISPLAY 0.489362 (-5590 2310);
PAINT MONO (-5590 2310);
FORCEPROP 2 LASTPIN (-6450 1700) $PN 31
J 2
(-6460 1710);
DISPLAY 0.489362 (-6460 1710);
PAINT MONO (-6460 1710);
FORCEPROP 2 LASTPIN (-6450 2100) $PN 35
J 2
(-6460 2110);
DISPLAY 0.489362 (-6460 2110);
PAINT MONO (-6460 2110);
FORCEPROP 2 LASTPIN (-5600 1650) $PN 6
J 0
(-5590 1660);
DISPLAY 0.489362 (-5590 1660);
PAINT MONO (-5590 1660);
FORCEPROP 2 LASTPIN (-5600 1600) $PN 41
J 0
(-5590 1610);
DISPLAY 0.489362 (-5590 1610);
PAINT MONO (-5590 1610);
FORCEPROP 2 LASTPIN (-6450 1950) $PN 38
J 2
(-6460 1960);
DISPLAY 0.489362 (-6460 1960);
PAINT MONO (-6460 1960);
FORCEPROP 2 LASTPIN (-6450 1650) $PN 37
J 2
(-6460 1660);
DISPLAY 0.489362 (-6460 1660);
PAINT MONO (-6460 1660);
FORCEPROP 2 LASTPIN (-5600 1450) $PN 5
J 0
(-5590 1460);
DISPLAY 0.489362 (-5590 1460);
PAINT MONO (-5590 1460);
FORCEPROP 2 LASTPIN (-5600 1400) $PN 7_9-20_24
J 0
(-5590 1410);
DISPLAY 0.489362 (-5590 1410);
PAINT MONO (-5590 1410);
FORCEPROP 2 LASTPIN (-5600 1350) $PN 40
J 0
(-5590 1360);
DISPLAY 0.489362 (-5590 1360);
PAINT MONO (-5590 1360);
FORCEPROP 2 LASTPIN (-5600 2050) $PN 32
J 0
(-5590 2060);
DISPLAY 0.489362 (-5590 2060);
PAINT MONO (-5590 2060);
FORCEPROP 2 LASTPIN (-6450 2600) $PN 4
J 2
(-6460 2610);
DISPLAY 0.489362 (-6460 2610);
PAINT MONO (-6460 2610);
FORCEPROP 2 LASTPIN (-6450 1350) $PN 34
J 2
(-6460 1360);
DISPLAY 0.489362 (-6460 1360);
PAINT MONO (-6460 1360);
FORCEPROP 2 LASTPIN (-6450 1850) $PN 39
J 2
(-6460 1860);
DISPLAY 0.489362 (-6460 1860);
PAINT MONO (-6460 1860);
FORCEPROP 2 LASTPIN (-5600 1950) $PN 10_19
J 0
(-5590 1960);
DISPLAY 0.489362 (-5590 1960);
PAINT MONO (-5590 1960);
FORCEPROP 2 LASTPIN (-6450 1450) $PN 36
J 2
(-6460 1460);
DISPLAY 0.489362 (-6460 1460);
PAINT MONO (-6460 1460);
FORCEPROP 2 LASTPIN (-6450 2300) $PN 3
J 2
(-6460 2310);
DISPLAY 0.489362 (-6460 2310);
PAINT MONO (-6460 2310);
FORCEPROP 2 LASTPIN (-5600 2600) $PN 25_29
J 0
(-5590 2610);
DISPLAY 0.489362 (-5590 2610);
PAINT MONO (-5590 2610);
FORCEPROP 2 LASTPIN (-5600 2550) $PN 30
J 0
(-5590 2560);
DISPLAY 0.489362 (-5590 2560);
PAINT MONO (-5590 2560);
FORCEPROP 2 LASTPIN (-5600 1700) $PN 1
J 0
(-5590 1710);
DISPLAY 0.489362 (-5590 1710);
PAINT MONO (-5590 1710);
FORCEPROP 2 LAST PART_TYPE SMLF
J 0
(-6300 2925);
DISPLAY 1.021277 (-6300 2925);
FORCEPROP 1 LAST MATERIAL IC
J 0
(-6300 2675);
DISPLAY 0.489362 (-6300 2675);
PAINT SKYBLUE (-6300 2675);
FORCEPROP 2 LAST VALUE ISL99390FRZ-TR5935
J 0
(-6300 2875);
DISPLAY 0.489362 (-6300 2875);
PAINT SKYBLUE (-6300 2875);
FORCEPROP 1 LAST PART_NUMBER AL099390004
J 0
(-6300 2750);
DISPLAY 0.489362 (-6300 2750);
PAINT SKYBLUE (-6300 2750);
FORCEPROP 1 LAST NEEDS_NO_SIZE TRUE
J 0
(-6000 1950);
DISPLAY 0.723404 (-6000 1950);
PAINT GREEN (-6000 1950);
DISPLAY INVISIBLE (-6000 1950);
FORCEPROP 1 LAST CDS_LMAN_SYM_OUTLINE -300,700,250,-650
J 0
(-6000 1950);
DISPLAY 0.468085 (-6000 1950);
PAINT GREEN (-6000 1950);
DISPLAY INVISIBLE (-6000 1950);
FORCEPROP 2 LAST CDS_LIB pure_quanta
J 0
(-6000 1950);
DISPLAY INVISIBLE (-6000 1950);
FORCEPROP 1 LAST PATH I84
J 0
(-6000 1950);
DISPLAY 0.723404 (-6000 1950);
PAINT GREEN (-6000 1950);
DISPLAY INVISIBLE (-6000 1950);
FORCEADD OFFPAGE..3
R 2
(-3900 1700);
FORCEPROP 2 LAST $XR0 192 
J 0
(-4180 1700);
DISPLAY 0.638298 (-4180 1700);
PAINT MONO (-4180 1700);
FORCEPROP 2 LAST PATH I86
J 2
(-4100 1775);
DISPLAY 1.021277 (-4100 1775);
DISPLAY INVISIBLE (-4100 1775);
FORCEPROP 1 LAST COMMENT_BODY TRUE
J 2
(-3850 1600);
DISPLAY 0.872340 (-3850 1600);
PAINT GREEN (-3850 1600);
DISPLAY INVISIBLE (-3850 1600);
FORCEPROP 1 LAST OFFPAGE TRUE
J 2
(-4225 1575);
DISPLAY 0.872340 (-4225 1575);
PAINT GREEN (-4225 1575);
DISPLAY INVISIBLE (-4225 1575);
FORCEPROP 2 LAST CDS_LIB standard
J 2
(-3900 1700);
DISPLAY INVISIBLE (-3900 1700);
FORCEADD Q_CAPP..1
(-2100 3050);
FORCEPROP 1 LAST LOCATION PC337
J 0
(-2050 3150);
DISPLAY 0.489362 (-2050 3150);
PAINT SKYBLUE (-2050 3150);
FORCEPROP 0 LAST $SEC 1
J 0
(-2050 3175);
DISPLAY 0.680851 (-2050 3175);
PAINT MONO (-2050 3175);
DISPLAY INVISIBLE (-2050 3175);
FORCEPROP 0 LAST CDS_SEC 1
J 0
(-2050 3175);
DISPLAY 1.021277 (-2050 3175);
DISPLAY INVISIBLE (-2050 3175);
FORCEPROP 1 LASTPIN (-2100 3150) $PN 1
J 0
(-2090 3135);
DISPLAY 0.489362 (-2090 3135);
PAINT MONO (-2090 3135);
FORCEPROP 1 LASTPIN (-2100 2950) $PN 2
J 0
(-2090 2935);
DISPLAY 0.489362 (-2090 2935);
PAINT MONO (-2090 2935);
FORCEPROP 1 LAST PACK_TYPE SMLF
J 0
(-2050 2900);
DISPLAY 0.489362 (-2050 2900);
PAINT SKYBLUE (-2050 2900);
FORCEPROP 1 LAST MATERIAL SPCAP
J 0
(-2050 2950);
DISPLAY 0.489362 (-2050 2950);
PAINT SKYBLUE (-2050 2950);
FORCEPROP 1 LAST TOLERANCE 20%
J 0
(-2050 3050);
DISPLAY 0.489362 (-2050 3050);
PAINT SKYBLUE (-2050 3050);
FORCEPROP 1 LAST VALUE 470UF
J 0
(-2050 3100);
DISPLAY 0.489362 (-2050 3100);
PAINT SKYBLUE (-2050 3100);
FORCEPROP 1 LAST PART_NUMBER CH747LM8825
J 0
(-2050 2850);
DISPLAY 0.489362 (-2050 2850);
PAINT SKYBLUE (-2050 2850);
FORCEPROP 1 LAST VOLTAGE 2.5V
J 0
(-2050 3000);
DISPLAY 0.489362 (-2050 3000);
PAINT SKYBLUE (-2050 3000);
FORCEPROP 2 LAST CDS_LIB pure_quanta
J 0
(-2100 3050);
DISPLAY INVISIBLE (-2100 3050);
FORCEPROP 1 LAST PATH I92
J 0
(-2050 3200);
DISPLAY 0.978723 (-2050 3200);
DISPLAY INVISIBLE (-2050 3200);
FORCEADD Q_CAPP..1
(-1750 3050);
FORCEPROP 1 LAST LOCATION PC340
J 0
(-1700 3150);
DISPLAY 0.489362 (-1700 3150);
PAINT SKYBLUE (-1700 3150);
FORCEPROP 0 LAST $SEC 1
J 0
(-1700 3175);
DISPLAY 0.680851 (-1700 3175);
PAINT MONO (-1700 3175);
DISPLAY INVISIBLE (-1700 3175);
FORCEPROP 0 LAST CDS_SEC 1
J 0
(-1700 3175);
DISPLAY 1.021277 (-1700 3175);
DISPLAY INVISIBLE (-1700 3175);
FORCEPROP 1 LASTPIN (-1750 3150) $PN 1
J 0
(-1740 3135);
DISPLAY 0.489362 (-1740 3135);
PAINT MONO (-1740 3135);
FORCEPROP 1 LASTPIN (-1750 2950) $PN 2
J 0
(-1740 2935);
DISPLAY 0.489362 (-1740 2935);
PAINT MONO (-1740 2935);
FORCEPROP 1 LAST MATERIAL EMPTY
J 0
(-1700 2950);
DISPLAY 0.489362 (-1700 2950);
PAINT RED (-1700 2950);
FORCEPROP 1 LAST TOLERANCE 20%
J 0
(-1700 3050);
DISPLAY 0.489362 (-1700 3050);
PAINT SKYBLUE (-1700 3050);
FORCEPROP 1 LAST VALUE 470UF
J 0
(-1700 3100);
DISPLAY 0.489362 (-1700 3100);
PAINT SKYBLUE (-1700 3100);
FORCEPROP 1 LAST PART_NUMBER CH747LM8825
J 0
(-1700 2850);
DISPLAY 0.489362 (-1700 2850);
PAINT SKYBLUE (-1700 2850);
FORCEPROP 1 LAST VOLTAGE 2.5V
J 0
(-1700 3000);
DISPLAY 0.489362 (-1700 3000);
PAINT SKYBLUE (-1700 3000);
FORCEPROP 1 LAST PACK_TYPE SMLF
J 0
(-1700 2900);
DISPLAY 0.489362 (-1700 2900);
PAINT SKYBLUE (-1700 2900);
FORCEPROP 2 LAST CDS_LIB pure_quanta
J 0
(-1750 3050);
DISPLAY INVISIBLE (-1750 3050);
FORCEPROP 1 LAST PATH I94
J 0
(-1700 3200);
DISPLAY 0.978723 (-1700 3200);
DISPLAY INVISIBLE (-1700 3200);
FORCEADD DNS..1
(-4700 4525);
PAINT RED (-4700 4525);
FORCEPROP 2 LAST CDS_LIB mstr_misc
J 0
(-4700 4525);
DISPLAY INVISIBLE (-4700 4525);
FORCEPROP 1 LAST COMMENT_BODY TRUE
R 1
J 0
(-4625 4300);
DISPLAY 0.872340 (-4625 4300);
PAINT GREEN (-4625 4300);
DISPLAY INVISIBLE (-4625 4300);
FORCEADD DNS..1
(-7150 1625);
PAINT RED (-7150 1625);
FORCEPROP 2 LAST CDS_LIB mstr_misc
J 0
(-7150 1625);
DISPLAY INVISIBLE (-7150 1625);
FORCEPROP 1 LAST COMMENT_BODY TRUE
R 1
J 0
(-7075 1400);
DISPLAY 0.872340 (-7075 1400);
PAINT GREEN (-7075 1400);
DISPLAY INVISIBLE (-7075 1400);
FORCEADD DNS..1
(-4625 1200);
PAINT RED (-4625 1200);
FORCEPROP 2 LAST CDS_LIB mstr_misc
J 0
(-4625 1200);
DISPLAY INVISIBLE (-4625 1200);
FORCEPROP 1 LAST COMMENT_BODY TRUE
R 1
J 0
(-4550 975);
DISPLAY 0.872340 (-4550 975);
PAINT GREEN (-4550 975);
DISPLAY INVISIBLE (-4550 975);
FORCEADD DNS..1
(-1750 3025);
PAINT RED (-1750 3025);
FORCEPROP 2 LAST CDS_LIB mstr_misc
J 0
(-1750 3025);
DISPLAY INVISIBLE (-1750 3025);
FORCEPROP 1 LAST COMMENT_BODY TRUE
R 1
J 0
(-1675 2800);
DISPLAY 0.872340 (-1675 2800);
PAINT GREEN (-1675 2800);
DISPLAY INVISIBLE (-1675 2800);
FORCEADD DNS..1
(-7175 4400);
PAINT RED (-7175 4400);
FORCEPROP 2 LAST CDS_LIB mstr_misc
J 0
(-7175 4400);
DISPLAY INVISIBLE (-7175 4400);
FORCEPROP 1 LAST COMMENT_BODY TRUE
R 1
J 0
(-7100 4175);
DISPLAY 0.872340 (-7100 4175);
PAINT GREEN (-7100 4175);
DISPLAY INVISIBLE (-7100 4175);
FORCEADD DNS..1
(-4625 1750);
PAINT RED (-4625 1750);
FORCEPROP 2 LAST CDS_LIB mstr_misc
J 0
(-4625 1750);
DISPLAY INVISIBLE (-4625 1750);
FORCEPROP 1 LAST COMMENT_BODY TRUE
R 1
J 0
(-4550 1525);
DISPLAY 0.872340 (-4550 1525);
PAINT GREEN (-4550 1525);
DISPLAY INVISIBLE (-4550 1525);
FORCEADD DNS..1
(-4700 4025);
PAINT RED (-4700 4025);
FORCEPROP 2 LAST CDS_LIB mstr_misc
J 0
(-4700 4025);
DISPLAY INVISIBLE (-4700 4025);
FORCEPROP 1 LAST COMMENT_BODY TRUE
R 1
J 0
(-4625 3800);
DISPLAY 0.872340 (-4625 3800);
PAINT GREEN (-4625 3800);
DISPLAY INVISIBLE (-4625 3800);
FORCEADD QUANTA_TITLE_BLOCK_C..1
(-425 -150);
FORCEPROP 0 LAST CDS_CON_LAST_MODIFIED Fri Mar 11 14:53:34 2022
J 0
(-2310 -135);
DISPLAY INVISIBLE (-2310 -135);
FORCEPROP 1 LAST CUSTOM_TXT_CDS <CON_LAST_MODIFIED>
J 0
(-2310 -135);
DISPLAY 0.978723 (-2310 -135);
FORCEPROP 2 LAST CUSTOM_TXT_CDS <XR_PAGE_TITLE>
J 0
(-8315 5100);
DISPLAY 0.638298 (-8315 5100);
PAINT PINK (-8315 5100);
DISPLAY INVISIBLE (-8315 5100);
FORCEPROP 1 LAST CUSTOM_TXT_CDS <NAME_2>
J 0
(-3600 -100);
FORCEPROP 1 LAST CUSTOM_TXT_CDS <NAME_1>
J 0
(-3600 25);
FORCEPROP 1 LAST CUSTOM_TXT_CDS <Q_NUMBER>
J 0
(-1828 -47);
DISPLAY 1.212766 (-1828 -47);
FORCEPROP 1 LAST CUSTOM_TXT_CDS <Q_PROJ>
J 0
(-2807 -48);
DISPLAY 1.212766 (-2807 -48);
FORCEPROP 1 LAST CUSTOM_TXT_CDS <Q_REV>
J 0
(-609 -47);
DISPLAY 1.212766 (-609 -47);
FORCEPROP 1 LAST CUSTOM_TXT_CDS <CON_PAGE_NUM> OF <CON_TOTAL_PAGES>
J 0
(-871 -132);
DISPLAY 0.978723 (-871 -132);
FORCEPROP 1 LAST Q_DEPT BU9
J 1
(-4188 -101);
DISPLAY 1.957447 (-4188 -101);
PAINT GREEN (-4188 -101);
FORCEPROP 1 LAST Q_TITLE PVDDCR_SOC_P1 VR PHASE 1&2
J 0
(-9725 -100);
DISPLAY 2.446809 (-9725 -100);
PAINT GREEN (-9725 -100);
FORCEPROP 2 LAST PAGE_BORDER TRUE
J 0
(-8315 5100);
DISPLAY 0.638298 (-8315 5100);
PAINT PINK (-8315 5100);
DISPLAY INVISIBLE (-8315 5100);
FORCEPROP 1 LAST CDS_LMAN_SYM_OUTLINE -9475,6775,100,-125
J 0
(-425 -150);
DISPLAY 0.468085 (-425 -150);
PAINT GREEN (-425 -150);
DISPLAY INVISIBLE (-425 -150);
FORCEPROP 2 LAST CDS_LIB pure_quanta
J 0
(-425 -150);
DISPLAY INVISIBLE (-425 -150);
FORCEPROP 1 LAST COMMENT_BODY TRUE
J 0
(-413 -163);
DISPLAY 0.978723 (-413 -163);
PAINT GREEN (-413 -163);
DISPLAY INVISIBLE (-413 -163);
FORCEPROP 2 LAST CDS_XR_PAGE_TITLE CR-191 : @T6G_MB_LIB.T6G(SCH_1):PAGE191
J 0
(-8315 5100);
DISPLAY 0.638298 (-8315 5100);
PAINT PINK (-8315 5100);
DISPLAY INVISIBLE (-8315 5100);
WIRE 16 -1 (-7525 4975)(-7525 4925);
WIRE 16 -1 (-7175 5550)(-7175 5425);
WIRE 16 -1 (-7500 2200)(-7500 2150);
WIRE 16 -1 (-7150 2775)(-7150 2650);
WIRE 16 -1 (-4675 3925)(-4675 3850);
WIRE 16 -1 (-4600 1100)(-4600 1025);
WIRE 16 -1 (-7825 1575)(-7825 1450);
WIRE 16 -1 (-7850 4350)(-7850 4225);
WIRE 16 -1 (-7250 1650)(-7500 1650);
WIRE 16 -1 (-7500 1650)(-7500 1525);
WIRE 16 -1 (-7275 4425)(-7525 4425);
WIRE 16 -1 (-7525 4425)(-7525 4300);
WIRE 16 -1 (-4600 1850)(-4600 1950);
WIRE 16 -1 (-4600 1950)(-3325 1950);
WIRE 16 -1 (-5600 1950)(-4600 1950);
FORCEPROP 2 LAST SIG_NAME SW_PVDDCR_SOC_P1_SW2
J 0
(-5485 1960);
DISPLAY 0.489362 (-5485 1960);
FORCEPROP 2 LASTPROP $XRERR UNIQUE?
J 0
(-5725 1960);
DISPLAY 0.638298 (-5725 1960);
PAINT MONO (-5725 1960);
DISPLAY INVISIBLE (-5725 1960);
WIRE 16 -1 (-3800 2075)(-3800 2050);
WIRE 16 -1 (-3800 2050)(-5600 2050);
FORCEPROP 2 LAST SIG_NAME SW_PVDDCR_SOC_P1_PH2
J 0
(-5485 2060);
DISPLAY 0.489362 (-5485 2060);
FORCEPROP 2 LASTPROP $XRERR UNIQUE?
J 0
(-5725 2060);
DISPLAY 0.638298 (-5725 2060);
PAINT MONO (-5725 2060);
DISPLAY INVISIBLE (-5725 2060);
WIRE 16 -1 (-3925 4850)(-3925 4825);
WIRE 16 -1 (-3925 4825)(-5625 4825);
FORCEPROP 2 LAST SIG_NAME SW_PVDDCR_SOC_P1_PH1
J 0
(-5535 4835);
DISPLAY 0.489362 (-5535 4835);
FORCEPROP 2 LASTPROP $XRERR UNIQUE?
J 0
(-5775 4835);
DISPLAY 0.638298 (-5775 4835);
PAINT MONO (-5775 4835);
DISPLAY INVISIBLE (-5775 4835);
WIRE 16 -1 (-4675 4625)(-4675 4725);
WIRE 16 -1 (-4675 4725)(-3575 4725);
WIRE 16 -1 (-5625 4725)(-4675 4725);
FORCEPROP 2 LAST SIG_NAME SW_PVDDCR_SOC_P1_SW1
J 0
(-5535 4735);
DISPLAY 0.489362 (-5535 4735);
FORCEPROP 2 LASTPROP $XRERR UNIQUE?
J 0
(-5775 4735);
DISPLAY 0.638298 (-5775 4735);
PAINT MONO (-5775 4735);
DISPLAY INVISIBLE (-5775 4735);
WIRE 16 -1 (-1950 4325)(-1550 4325);
WIRE 16 -1 (-1950 4325)(-1950 4425);
WIRE 16 -1 (-1125 4325)(-1550 4325);
WIRE 16 -1 (-1550 4450)(-1550 4325);
WIRE 16 -1 (-850 4325)(-1125 4325);
WIRE 16 -1 (-1125 4450)(-1125 4325);
WIRE 16 -1 (-850 4425)(-850 4325);
WIRE 16 -1 (-850 4200)(-850 4325);
WIRE 16 -1 (-2775 5800)(-2775 5750);
WIRE 16 -1 (-2775 5750)(-2950 5750);
WIRE 16 -1 (-2300 4400)(-2300 4475);
WIRE 16 -1 (-2300 4475)(-2775 4475);
WIRE 16 -1 (-4675 5075)(-3925 5075);
FORCEPROP 2 LAST SIG_NAME SW_PVDDCR_SOC_P1_BOOT1_RC
J 2
(-3960 5085);
DISPLAY 0.489362 (-3960 5085);
FORCEPROP 2 LASTPROP $XRERR UNIQUE?
J 0
(-4200 5085);
DISPLAY 0.638298 (-4200 5085);
PAINT MONO (-4200 5085);
DISPLAY INVISIBLE (-4200 5085);
WIRE 16 -1 (-3925 5075)(-3925 5050);
WIRE 16 -1 (-1675 1675)(-1675 1550);
WIRE 16 -1 (-1250 1550)(-1675 1550);
WIRE 16 -1 (-1250 1675)(-1250 1550);
WIRE 16 -1 (-1250 1475)(-1250 1550);
WIRE 16 -1 (-1875 1950)(-1875 775);
WIRE 16 -1 (-2525 1950)(-1875 1950);
WIRE 16 -1 (-1875 1950)(-1675 1950);
WIRE 16 -1 (-1875 775)(-4150 775);
WIRE 16 -1 (-1675 1950)(-1250 1950);
WIRE 16 -1 (-1675 1950)(-1675 1875);
WIRE 16 -1 (-1250 2050)(-1250 1950);
WIRE 16 -1 (-1250 1950)(-1250 1875);
WIRE 16 -1 (-4575 2300)(-3800 2300);
FORCEPROP 2 LAST SIG_NAME SW_PVDDCR_SOC_P1_BOOT2_RC
J 2
(-3835 2310);
DISPLAY 0.489362 (-3835 2310);
FORCEPROP 2 LASTPROP $XRERR UNIQUE?
J 0
(-4075 2310);
DISPLAY 0.638298 (-4075 2310);
PAINT MONO (-4075 2310);
DISPLAY INVISIBLE (-4075 2310);
WIRE 16 -1 (-3800 2300)(-3800 2275);
WIRE 16 -1 (-2125 1700)(-2525 1700);
FORCEPROP 2 LAST SIG_NAME IND_SOC_P1_CPL2
J 0
(-2460 1710);
DISPLAY 0.489362 (-2460 1710);
WIRE 16 -1 (-3850 1700)(-3325 1700);
FORCEPROP 2 LAST SIG_NAME IND_SOC_P1_CPL3
J 0
(-3785 1710);
DISPLAY 0.489362 (-3785 1710);
WIRE 16 -1 (-4675 4425)(-4675 4125);
FORCEPROP 2 LAST SIG_NAME SW_PVDDCR_SOC_P1_SW1_RC
J 0
(-4635 4235);
DISPLAY 0.489362 (-4635 4235);
FORCEPROP 2 LASTPROP $XRERR UNIQUE?
J 0
(-4875 4235);
DISPLAY 0.638298 (-4875 4235);
PAINT MONO (-4875 4235);
DISPLAY INVISIBLE (-4875 4235);
WIRE 16 -1 (-5625 5075)(-4875 5075);
FORCEPROP 2 LAST SIG_NAME SW_PVDDCR_SOC_P1_BOOT1
J 0
(-5535 5085);
DISPLAY 0.489362 (-5535 5085);
FORCEPROP 2 LASTPROP $XRERR UNIQUE?
J 0
(-5775 5085);
DISPLAY 0.638298 (-5775 5085);
PAINT MONO (-5775 5085);
DISPLAY INVISIBLE (-5775 5085);
WIRE 16 -1 (-5625 4375)(-5100 4375);
FORCEPROP 2 LAST SIG_NAME NC_PVDDCR_SOC_P1_GL2_1
J 0
(-5535 4385);
DISPLAY 0.489362 (-5535 4385);
FORCEPROP 2 LASTPROP $XRERR UNIQUE?
J 0
(-5070 4375);
DISPLAY 0.638298 (-5070 4375);
PAINT MONO (-5070 4375);
DISPLAY INVISIBLE (-5070 4375);
WIRE 16 -1 (-5625 4425)(-5100 4425);
FORCEPROP 2 LAST SIG_NAME NC_PVDDCR_SOC_P1_GL1_1
J 0
(-5535 4435);
DISPLAY 0.489362 (-5535 4435);
FORCEPROP 2 LASTPROP $XRERR UNIQUE?
J 0
(-5070 4425);
DISPLAY 0.638298 (-5070 4425);
PAINT MONO (-5070 4425);
DISPLAY INVISIBLE (-5070 4425);
WIRE 16 -1 (-5450 4050)(-5450 4125);
WIRE 16 -1 (-5450 4125)(-5450 4175);
WIRE 16 -1 (-5625 4125)(-5450 4125);
WIRE 16 -1 (-5625 4175)(-5450 4175);
WIRE 16 -1 (-5450 4175)(-5450 4225);
WIRE 16 -1 (-5625 4225)(-5450 4225);
WIRE 16 -1 (-5450 4275)(-5450 4225);
WIRE 16 -1 (-5450 4275)(-5625 4275);
WIRE 16 -1 (-6475 4225)(-7100 4225);
FORCEPROP 2 LAST SIG_NAME PVDDCR_SOC_P1_TEMP1
J 2
(-6535 4235);
DISPLAY 0.489362 (-6535 4235);
WIRE 16 -1 (-6475 4725)(-7125 4725);
FORCEPROP 2 LAST SIG_NAME PVDDCR_SOC_P1_IMON1
J 2
(-6535 4735);
DISPLAY 0.489362 (-6535 4735);
WIRE 16 -1 (-6475 4125)(-7075 4125);
FORCEPROP 2 LAST SIG_NAME PVDDCR_SOC_P1_PWM1
J 2
(-6535 4135);
DISPLAY 0.489362 (-6535 4135);
WIRE 16 -1 (-6475 4475)(-6925 4475);
FORCEPROP 2 LAST SIG_NAME NC_PVDDCR_SOC_P1_DNC1
J 2
(-6535 4485);
DISPLAY 0.489362 (-6535 4485);
FORCEPROP 2 LASTPROP $XRERR UNIQUE?
J 0
(-7165 4475);
DISPLAY 0.638298 (-7165 4475);
PAINT MONO (-7165 4475);
DISPLAY INVISIBLE (-7165 4475);
WIRE 16 -1 (-7075 4425)(-6475 4425);
FORCEPROP 2 LAST SIG_NAME PVDDCR_SOC_P1_LSET1
J 2
(-6535 4435);
DISPLAY 0.489362 (-6535 4435);
FORCEPROP 2 LASTPROP $XRERR UNIQUE?
J 0
(-6775 4435);
DISPLAY 0.638298 (-6775 4435);
PAINT MONO (-6775 4435);
DISPLAY INVISIBLE (-6775 4435);
WIRE 16 -1 (-7525 5250)(-7050 5250);
WIRE 16 -1 (-7525 5525)(-7525 5250);
WIRE 16 -1 (-7525 5250)(-7525 5175);
WIRE 16 -1 (-7050 5250)(-7050 5075);
FORCEPROP 2 LAST SIG_NAME PVDDCR_SOC_P1_VCC1
J 2
(-6560 5085);
DISPLAY 0.489362 (-6560 5085);
FORCEPROP 2 LASTPROP $XRERR UNIQUE?
J 0
(-6800 5085);
DISPLAY 0.638298 (-6800 5085);
PAINT MONO (-6800 5085);
DISPLAY INVISIBLE (-6800 5085);
WIRE 16 -1 (-7050 5075)(-6475 5075);
WIRE 16 -1 (-7050 5075)(-7050 4875);
WIRE 16 -1 (-7050 4875)(-6475 4875);
WIRE 16 -1 (-7850 4550)(-7850 4625);
WIRE 16 -1 (-6475 4625)(-7850 4625);
FORCEPROP 2 LAST SIG_NAME PVDDCR_CPU0_P1_VCCS
J 2
(-6535 4635);
DISPLAY 0.489362 (-6535 4635);
WIRE 16 -1 (-8025 4625)(-7850 4625);
WIRE 16 -1 (-7525 5725)(-7525 5850);
WIRE 16 -1 (-7175 5850)(-7525 5850);
WIRE 16 -1 (-7525 5975)(-7525 5850);
WIRE 16 -1 (-6850 5850)(-7175 5850);
WIRE 16 -1 (-7175 5750)(-7175 5850);
WIRE 16 -1 (-6850 5375)(-6850 5850);
WIRE 16 -1 (-6850 5375)(-6475 5375);
WIRE 16 -1 (-5350 2750)(-5350 2625);
WIRE 16 -1 (-5350 2625)(-4975 2625);
WIRE 16 -1 (-4975 2625)(-4650 2625);
WIRE 16 -1 (-4975 2750)(-4975 2625);
WIRE 16 -1 (-4650 2625)(-4325 2625);
WIRE 16 -1 (-4650 2750)(-4650 2625);
WIRE 16 -1 (-4025 2625)(-4325 2625);
WIRE 16 -1 (-4325 2750)(-4325 2625);
WIRE 16 -1 (-3700 2625)(-4025 2625);
WIRE 16 -1 (-4025 2750)(-4025 2625);
WIRE 16 -1 (-3700 2625)(-3700 2575);
WIRE 16 -1 (-3700 2750)(-3700 2625);
WIRE 16 -1 (-5600 2300)(-4775 2300);
FORCEPROP 2 LAST SIG_NAME SW_PVDDCR_SOC_P1_BOOT2
J 0
(-5485 2310);
DISPLAY 0.489362 (-5485 2310);
FORCEPROP 2 LASTPROP $XRERR UNIQUE?
J 0
(-5725 2310);
DISPLAY 0.638298 (-5725 2310);
PAINT MONO (-5725 2310);
DISPLAY INVISIBLE (-5725 2310);
WIRE 16 -1 (-4600 1650)(-4600 1300);
FORCEPROP 2 LAST SIG_NAME SW_PVDDCR_SOC_P1_SW2_RC
J 0
(-4560 1460);
DISPLAY 0.489362 (-4560 1460);
FORCEPROP 2 LASTPROP $XRERR UNIQUE?
J 0
(-4800 1460);
DISPLAY 0.638298 (-4800 1460);
PAINT MONO (-4800 1460);
DISPLAY INVISIBLE (-4800 1460);
WIRE 16 -1 (-5600 1600)(-5075 1600);
FORCEPROP 2 LAST SIG_NAME NC_PVDDCR_SOC_P1_GL2_2
J 0
(-5485 1610);
DISPLAY 0.489362 (-5485 1610);
FORCEPROP 2 LASTPROP $XRERR UNIQUE?
J 0
(-5045 1600);
DISPLAY 0.638298 (-5045 1600);
PAINT MONO (-5045 1600);
DISPLAY INVISIBLE (-5045 1600);
WIRE 16 -1 (-5600 1650)(-5075 1650);
FORCEPROP 2 LAST SIG_NAME NC_PVDDCR_SOC_P1_GL1_2
J 0
(-5485 1660);
DISPLAY 0.489362 (-5485 1660);
FORCEPROP 2 LASTPROP $XRERR UNIQUE?
J 0
(-5045 1650);
DISPLAY 0.638298 (-5045 1650);
PAINT MONO (-5045 1650);
DISPLAY INVISIBLE (-5045 1650);
WIRE 16 -1 (-5600 1350)(-5425 1350);
WIRE 16 -1 (-5425 1300)(-5425 1350);
WIRE 16 -1 (-5425 1350)(-5425 1400);
WIRE 16 -1 (-5600 1400)(-5425 1400);
WIRE 16 -1 (-5425 1400)(-5425 1450);
WIRE 16 -1 (-5600 1450)(-5425 1450);
WIRE 16 -1 (-5425 1500)(-5425 1450);
WIRE 16 -1 (-5425 1500)(-5600 1500);
WIRE 16 -1 (-7500 2475)(-7000 2475);
WIRE 16 -1 (-7500 2750)(-7500 2475);
WIRE 16 -1 (-7500 2475)(-7500 2400);
WIRE 16 -1 (-7000 2475)(-7000 2300);
FORCEPROP 2 LAST SIG_NAME PVDDCR_SOC_P1_VCC2
J 2
(-6535 2310);
DISPLAY 0.489362 (-6535 2310);
FORCEPROP 2 LASTPROP $XRERR UNIQUE?
J 0
(-6775 2310);
DISPLAY 0.638298 (-6775 2310);
PAINT MONO (-6775 2310);
DISPLAY INVISIBLE (-6775 2310);
WIRE 16 -1 (-7000 2300)(-6450 2300);
WIRE 16 -1 (-7000 2300)(-7000 2100);
WIRE 16 -1 (-7000 2100)(-6450 2100);
WIRE 16 -1 (-7500 2950)(-7500 3075);
WIRE 16 -1 (-7150 3075)(-7500 3075);
WIRE 16 -1 (-7500 3200)(-7500 3075);
WIRE 16 -1 (-6825 3075)(-7150 3075);
WIRE 16 -1 (-7150 2975)(-7150 3075);
WIRE 16 -1 (-6825 2600)(-6825 3075);
WIRE 16 -1 (-6825 2600)(-6450 2600);
WIRE 16 -1 (-6450 1950)(-7100 1950);
FORCEPROP 2 LAST SIG_NAME PVDDCR_SOC_P1_IMON2
J 2
(-6510 1960);
DISPLAY 0.489362 (-6510 1960);
WIRE 16 -1 (-6450 1450)(-7075 1450);
FORCEPROP 2 LAST SIG_NAME PVDDCR_SOC_P1_TEMP1
J 2
(-6510 1460);
DISPLAY 0.489362 (-6510 1460);
WIRE 16 -1 (-6450 1350)(-7050 1350);
FORCEPROP 2 LAST SIG_NAME PVDDCR_SOC_P1_PWM2
J 2
(-6510 1360);
DISPLAY 0.489362 (-6510 1360);
WIRE 16 -1 (-7050 1650)(-6450 1650);
FORCEPROP 2 LAST SIG_NAME PVDDCR_SOC_P1_LSET2
J 2
(-6510 1660);
DISPLAY 0.489362 (-6510 1660);
FORCEPROP 2 LASTPROP $XRERR UNIQUE?
J 0
(-6750 1660);
DISPLAY 0.638298 (-6750 1660);
PAINT MONO (-6750 1660);
DISPLAY INVISIBLE (-6750 1660);
WIRE 16 -1 (-6450 1700)(-6900 1700);
FORCEPROP 2 LAST SIG_NAME NC_PVDDCR_SOC_P1_DNC2
J 2
(-6510 1710);
DISPLAY 0.489362 (-6510 1710);
FORCEPROP 2 LASTPROP $XRERR UNIQUE?
J 0
(-7140 1700);
DISPLAY 0.638298 (-7140 1700);
PAINT MONO (-7140 1700);
DISPLAY INVISIBLE (-7140 1700);
WIRE 16 -1 (-8000 1850)(-7825 1850);
WIRE 16 -1 (-6450 1850)(-7825 1850);
FORCEPROP 2 LAST SIG_NAME PVDDCR_CPU0_P1_VCCS
J 2
(-6510 1860);
DISPLAY 0.489362 (-6510 1860);
WIRE 16 -1 (-7825 1775)(-7825 1850);
WIRE 16 -1 (-3425 5675)(-3425 5750);
WIRE 16 -1 (-3150 5750)(-3425 5750);
WIRE 16 -1 (-3425 5750)(-3825 5750);
WIRE 16 -1 (-3825 5675)(-3825 5750);
WIRE 16 -1 (-3900 5750)(-3825 5750);
WIRE 16 -1 (-3900 5800)(-3900 5750);
WIRE 16 -1 (-4150 5750)(-3900 5750);
WIRE 16 -1 (-4150 5750)(-4150 5675);
WIRE 16 -1 (-4450 5750)(-4150 5750);
WIRE 16 -1 (-4450 5750)(-4450 5675);
WIRE 16 -1 (-4775 5750)(-4450 5750);
WIRE 16 -1 (-4775 5675)(-4775 5750);
WIRE 16 -1 (-5100 5750)(-4775 5750);
WIRE 16 -1 (-5100 5675)(-5100 5750);
WIRE 16 -1 (-5425 5750)(-5100 5750);
WIRE 16 -1 (-5425 5675)(-5425 5750);
WIRE 16 -1 (-5525 5750)(-5425 5750);
WIRE 16 -1 (-5525 5750)(-5525 5375);
WIRE 16 -1 (-5625 5375)(-5525 5375);
WIRE 16 -1 (-5525 5375)(-5525 5325);
WIRE 16 -1 (-5525 5325)(-5625 5325);
WIRE 16 -1 (-3425 5475)(-3425 5350);
WIRE 16 -1 (-3425 5350)(-3825 5350);
WIRE 16 -1 (-3825 5350)(-3825 5475);
WIRE 16 -1 (-3900 5350)(-3825 5350);
WIRE 16 -1 (-3900 5300)(-3900 5350);
WIRE 16 -1 (-4150 5350)(-3900 5350);
WIRE 16 -1 (-4150 5475)(-4150 5350);
WIRE 16 -1 (-4150 5350)(-4450 5350);
WIRE 16 -1 (-4450 5475)(-4450 5350);
WIRE 16 -1 (-4775 5350)(-4450 5350);
WIRE 16 -1 (-4775 5475)(-4775 5350);
WIRE 16 -1 (-5100 5350)(-4775 5350);
WIRE 16 -1 (-5100 5475)(-5100 5350);
WIRE 16 -1 (-5425 5350)(-5100 5350);
WIRE 16 -1 (-5425 5475)(-5425 5350);
WIRE 16 -1 (-4075 4475)(-3575 4475);
FORCEPROP 2 LAST SIG_NAME IND_SOC_P1_CPL2
J 0
(-3985 4485);
DISPLAY 0.489362 (-3985 4485);
WIRE 16 -1 (-5625 4475)(-4900 4475);
WIRE 16 -1 (-4900 4475)(-4900 3700);
WIRE 16 -1 (-4300 3700)(-4900 3700);
FORCEPROP 2 LAST SIG_NAME PVDDCR_SOC_P1_VOS1
J 0
(-5535 4500);
DISPLAY 0.489362 (-5535 4500);
FORCEPROP 2 LASTPROP $XRERR UNIQUE?
J 0
(-5775 4500);
DISPLAY 0.638298 (-5775 4500);
PAINT MONO (-5775 4500);
DISPLAY INVISIBLE (-5775 4500);
WIRE 16 -1 (-1425 3250)(-1425 3275);
WIRE 16 -1 (-1425 3150)(-1425 3250);
WIRE 16 -1 (-1425 3250)(-1750 3250);
WIRE 16 -1 (-1750 3150)(-1750 3250);
WIRE 16 -1 (-2100 3250)(-1750 3250);
WIRE 16 -1 (-2100 3150)(-2100 3250);
WIRE 16 -1 (-1425 2750)(-1425 2800);
WIRE 16 -1 (-1425 2950)(-1425 2800);
WIRE 16 -1 (-1425 2800)(-1750 2800);
WIRE 16 -1 (-1750 2950)(-1750 2800);
WIRE 16 -1 (-1750 2800)(-2100 2800);
WIRE 16 -1 (-2100 2950)(-2100 2800);
WIRE 17 273 (-900 2475)(-900 3550);
WIRE 17 273 (-900 2475)(-2500 2475);
WIRE 17 273 (-2500 3550)(-900 3550);
WIRE 17 273 (-2500 2475)(-2500 3550);
WIRE 16 -1 (-3700 3100)(-3700 3025);
WIRE 16 -1 (-3700 3025)(-3700 2950);
WIRE 16 -1 (-3700 3025)(-4025 3025);
WIRE 16 -1 (-4025 3025)(-4025 2950);
WIRE 16 -1 (-4325 3025)(-4025 3025);
WIRE 16 -1 (-4325 3025)(-4325 2950);
WIRE 16 -1 (-4650 3025)(-4325 3025);
WIRE 16 -1 (-4650 2950)(-4650 3025);
WIRE 16 -1 (-4975 3025)(-4650 3025);
WIRE 16 -1 (-4975 2950)(-4975 3025);
WIRE 16 -1 (-5350 3025)(-4975 3025);
WIRE 16 -1 (-5350 3025)(-5350 2950);
WIRE 16 -1 (-5500 3025)(-5350 3025);
WIRE 16 -1 (-5500 3025)(-5500 2600);
WIRE 16 -1 (-5500 2600)(-5500 2550);
WIRE 16 -1 (-5600 2600)(-5500 2600);
WIRE 16 -1 (-5500 2550)(-5600 2550);
WIRE 16 -1 (-4100 3700)(-2025 3700);
WIRE 16 -1 (-2025 4725)(-2025 3700);
WIRE 16 -1 (-2025 4725)(-1950 4725);
WIRE 16 -1 (-2775 4725)(-2025 4725);
WIRE 16 -1 (-1550 4725)(-1950 4725);
WIRE 16 -1 (-1950 4625)(-1950 4725);
WIRE 16 -1 (-1125 4725)(-1550 4725);
WIRE 16 -1 (-1550 4725)(-1550 4650);
WIRE 16 -1 (-850 4725)(-1125 4725);
WIRE 16 -1 (-1125 4725)(-1125 4650);
WIRE 16 -1 (-850 4800)(-850 4725);
WIRE 16 -1 (-850 4725)(-850 4625);
WIRE 16 -1 (-4350 775)(-4850 775);
FORCEPROP 2 LAST SIG_NAME PVDDCR_SOC_P1_VOS2
J 0
(-5485 1725);
DISPLAY 0.489362 (-5485 1725);
FORCEPROP 2 LASTPROP $XRERR UNIQUE?
J 0
(-5725 1725);
DISPLAY 0.638298 (-5725 1725);
PAINT MONO (-5725 1725);
DISPLAY INVISIBLE (-5725 1725);
WIRE 16 -1 (-4850 775)(-4850 1700);
WIRE 16 -1 (-5600 1700)(-4850 1700);
DOT 1 (-1750 2800);
DOT 1 (-4975 2625);
DOT 1 (-1250 1550);
DOT 1 (-4775 5350);
DOT 1 (-5100 5750);
DOT 1 (-2025 4725);
DOT 1 (-4450 5350);
DOT 1 (-4150 5350);
DOT 1 (-3900 5350);
DOT 1 (-3825 5350);
DOT 1 (-7175 5850);
DOT 1 (-3825 5750);
DOT 1 (-5425 5750);
DOT 1 (-7850 4625);
DOT 1 (-4450 5750);
DOT 1 (-3425 5750);
DOT 1 (-7050 5075);
DOT 1 (-4775 5750);
DOT 1 (-5100 5350);
DOT 1 (-5525 5375);
DOT 1 (-5450 4225);
DOT 1 (-5450 4175);
DOT 1 (-5450 4125);
DOT 1 (-7525 5850);
DOT 1 (-7525 5250);
DOT 1 (-3900 5750);
DOT 1 (-1125 4325);
DOT 1 (-850 4725);
DOT 1 (-850 4325);
DOT 1 (-1125 4725);
DOT 1 (-1550 4725);
DOT 1 (-1950 4725);
DOT 1 (-1550 4325);
DOT 1 (-1250 1950);
DOT 1 (-1675 1950);
DOT 1 (-1875 1950);
DOT 1 (-3700 3025);
DOT 1 (-3700 2625);
DOT 1 (-4025 3025);
DOT 1 (-4025 2625);
DOT 1 (-4325 3025);
DOT 1 (-4325 2625);
DOT 1 (-4650 3025);
DOT 1 (-4650 2625);
DOT 1 (-4975 3025);
DOT 1 (-5350 3025);
DOT 1 (-5500 2600);
DOT 1 (-5425 1400);
DOT 1 (-5425 1450);
DOT 1 (-5425 1350);
DOT 1 (-7150 3075);
DOT 1 (-7500 3075);
DOT 1 (-7000 2300);
DOT 1 (-7500 2475);
DOT 1 (-7825 1850);
DOT 1 (-1425 3250);
DOT 1 (-1425 2800);
DOT 1 (-1750 3250);
DOT 1 (-4675 4725);
DOT 1 (-4150 5750);
DOT 1 (-4600 1950);
FORCENOTE
PR207,PR208,PR214 = CS00002JB38
(-9600 475) 0;
DISPLAY LEFT (-9600 475);
DISPLAY 1.021277 (-9600 475);
PAINT WHITE (-9600 475);
FORCENOTE
3RD SOURCE:MPS BOM
(-9600 375) 0;
DISPLAY LEFT (-9600 375);
DISPLAY 1.021277 (-9600 375);
PAINT WHITE (-9600 375);
FORCENOTE
PR209,PR210,PR215=CS00002JB38
(-9600 150) 0;
DISPLAY LEFT (-9600 150);
DISPLAY 1.021277 (-9600 150);
PAINT WHITE (-9600 150);
FORCENOTE
PR211,PR212,PR216=EMPTY
(-9600 225) 0;
DISPLAY LEFT (-9600 225);
DISPLAY 1.021277 (-9600 225);
PAINT WHITE (-9600 225);
FORCENOTE
PC317_7,PC318_8,PC345_9=EMPTY
(-9600 300) 0;
DISPLAY LEFT (-9600 300);
DISPLAY 1.021277 (-9600 300);
PAINT WHITE (-9600 300);
FORCENOTE
PR209,PR210,PR215 = CS00002JB38
(-9600 700) 0;
DISPLAY LEFT (-9600 700);
DISPLAY 1.021277 (-9600 700);
PAINT WHITE (-9600 700);
FORCENOTE
PC317_7,PC318_8,PC345_9 = EMPTY
(-9600 550) 0;
DISPLAY LEFT (-9600 550);
DISPLAY 1.021277 (-9600 550);
PAINT WHITE (-9600 550);
FORCENOTE
PR211,PR212,PR216 = EMPTY
(-9600 625) 0;
DISPLAY LEFT (-9600 625);
DISPLAY 1.021277 (-9600 625);
PAINT WHITE (-9600 625);
FORCENOTE
PU30,PU31,PU32 = AL021590000/TDA21590
(-9600 775) 0;
DISPLAY LEFT (-9600 775);
DISPLAY 1.021277 (-9600 775);
PAINT WHITE (-9600 775);
FORCENOTE
PU30,PU31,PU32=AL099390004/ISL99390FRZ-TR5935
(-9600 1000) 0;
DISPLAY LEFT (-9600 1000);
DISPLAY 1.021277 (-9600 1000);
PAINT WHITE (-9600 1000);
FORCENOTE
MAIN SOURCE:RENESAS BOM
(-9600 1075) 0;
DISPLAY LEFT (-9600 1075);
DISPLAY 1.021277 (-9600 1075);
PAINT WHITE (-9600 1075);
FORCENOTE
PVDDCR_SOC_P1_PHASE1
(-6600 6125) 0;
DISPLAY LEFT (-6600 6125);
DISPLAY 1.595745 (-6600 6125);
PAINT WHITE (-6600 6125);
FORCENOTE
ESR=4.5M OHM
(-1925 2725) 0;
DISPLAY LEFT (-1925 2725);
DISPLAY 0.638298 (-1925 2725);
PAINT WHITE (-1925 2725);
FORCENOTE
7.3*4.3*1.9
(-1925 2675) 0;
DISPLAY LEFT (-1925 2675);
DISPLAY 0.638298 (-1925 2675);
PAINT WHITE (-1925 2675);
FORCENOTE
2ND=CH747LM8822
(-1925 2625) 0;
DISPLAY LEFT (-1925 2625);
DISPLAY 0.638298 (-1925 2625);
PAINT WHITE (-1925 2625);
FORCENOTE
2ND=CV+15^0TZ01
(-2550 2025) 0;
DISPLAY LEFT (-2550 2025);
DISPLAY 0.638298 (-2550 2025);
PAINT WHITE (-2550 2025);
FORCENOTE
11.0*7.5*12.5
(-2550 2175) 0;
DISPLAY LEFT (-2550 2175);
DISPLAY 0.638298 (-2550 2175);
PAINT WHITE (-2550 2175);
FORCENOTE
DCR=1-4,0.105M OHM
(-2550 2125) 0;
DISPLAY LEFT (-2550 2125);
DISPLAY 0.638298 (-2550 2125);
PAINT WHITE (-2550 2125);
FORCENOTE
DCR=2-3,0.27M OHM
(-2550 2075) 0;
DISPLAY LEFT (-2550 2075);
DISPLAY 0.638298 (-2550 2075);
PAINT WHITE (-2550 2075);
FORCENOTE
IRIPPLE:4.65A
(-3725 5250) 0;
DISPLAY LEFT (-3725 5250);
DISPLAY 0.638298 (-3725 5250);
PAINT WHITE (-3725 5250);
FORCENOTE
8*11.5
(-3725 5200) 0;
DISPLAY LEFT (-3725 5200);
DISPLAY 0.638298 (-3725 5200);
PAINT WHITE (-3725 5200);
FORCENOTE
2ND=CC72204MD01
(-3725 5150) 0;
DISPLAY LEFT (-3725 5150);
DISPLAY 0.638298 (-3725 5150);
PAINT WHITE (-3725 5150);
FORCENOTE
3RD=CC72204MD03
(-3725 5100) 0;
DISPLAY LEFT (-3725 5100);
DISPLAY 0.638298 (-3725 5100);
PAINT WHITE (-3725 5100);
FORCENOTE
ESR=16M OHM
(-3725 5300) 0;
DISPLAY LEFT (-3725 5300);
DISPLAY 0.638298 (-3725 5300);
PAINT WHITE (-3725 5300);
FORCENOTE
PVDDCR_SOC_P1_PHASE2
(-6575 3350) 0;
DISPLAY LEFT (-6575 3350);
DISPLAY 1.595745 (-6575 3350);
PAINT WHITE (-6575 3350);
FORCENOTE
2ND SOURCE:INFENEON BOM
(-9600 850) 0;
DISPLAY LEFT (-9600 850);
DISPLAY 1.021277 (-9600 850);
PAINT WHITE (-9600 850);
FORCENOTE
BOM NOTE
(-9600 1175) 0;
DISPLAY LEFT (-9600 1175);
DISPLAY 1.021277 (-9600 1175);
PAINT WHITE (-9600 1175);
FORCENOTE
PGL6303.151HLT
(-2800 5025) 0;
DISPLAY LEFT (-2800 5025);
DISPLAY 0.638298 (-2800 5025);
PAINT WHITE (-2800 5025);
FORCENOTE
ISAT:70A@100C
(-2800 4975) 0;
DISPLAY LEFT (-2800 4975);
DISPLAY 0.638298 (-2800 4975);
PAINT WHITE (-2800 4975);
FORCENOTE
11.0*7.5*12.5
(-2800 4925) 0;
DISPLAY LEFT (-2800 4925);
DISPLAY 0.638298 (-2800 4925);
PAINT WHITE (-2800 4925);
FORCENOTE
DCR=1-4,0.105M OHM
(-2800 4875) 0;
DISPLAY LEFT (-2800 4875);
DISPLAY 0.638298 (-2800 4875);
PAINT WHITE (-2800 4875);
FORCENOTE
DCR=2-3,0.27M OHM
(-2800 4825) 0;
DISPLAY LEFT (-2800 4825);
DISPLAY 0.638298 (-2800 4825);
PAINT WHITE (-2800 4825);
FORCENOTE
ISAT:70A@100C
(-2550 2225) 0;
DISPLAY LEFT (-2550 2225);
DISPLAY 0.638298 (-2550 2225);
PAINT WHITE (-2550 2225);
FORCENOTE
PGL6303.151HLT
(-2550 2275) 0;
DISPLAY LEFT (-2550 2275);
DISPLAY 0.638298 (-2550 2275);
PAINT WHITE (-2550 2275);
FORCENOTE
PG2292.500HLT
(-3200 5675) 0;
DISPLAY LEFT (-3200 5675);
DISPLAY 0.638298 (-3200 5675);
PAINT WHITE (-3200 5675);
FORCENOTE
ISAT:70A@100C
(-3200 5625) 0;
DISPLAY LEFT (-3200 5625);
DISPLAY 0.638298 (-3200 5625);
PAINT WHITE (-3200 5625);
FORCENOTE
6.0*6.1*7.0
(-3200 5575) 0;
DISPLAY LEFT (-3200 5575);
DISPLAY 0.638298 (-3200 5575);
PAINT WHITE (-3200 5575);
FORCENOTE
DCR=0.09M OHM
(-3200 5525) 0;
DISPLAY LEFT (-3200 5525);
DISPLAY 0.638298 (-3200 5525);
PAINT WHITE (-3200 5525);
FORCENOTE
2ND=CVA50^0MZ07
(-3200 5475) 0;
DISPLAY LEFT (-3200 5475);
DISPLAY 0.638298 (-3200 5475);
PAINT WHITE (-3200 5475);
FORCENOTE
3RD=CVA50^0MZ08
(-3200 5425) 0;
DISPLAY LEFT (-3200 5425);
DISPLAY 0.638298 (-3200 5425);
PAINT WHITE (-3200 5425);
FORCENOTE
2ND=CV+15^0TZ01
(-2800 4775) 0;
DISPLAY LEFT (-2800 4775);
DISPLAY 0.638298 (-2800 4775);
PAINT WHITE (-2800 4775);
QUIT
